FILE_TYPE = MACRO_DRAWING;
SET COLOR_WIRE YELLOW;
SET COLOR_PROP MONO;
SET COLOR_DOT WHITE;
SET COLOR_ARC YELLOW;
SET COLOR_BODY GREEN;
SET COLOR_NOTE MONO;
SET PROP_DISPLAY VALUE;
SET PAGE_NUMBER P243;
FORCEADD GND..1
(-7750 1450);
FORCEPROP 3 LASTPIN (-7750 1500) SIG_NAME GND\g
J 0
(-7740 1510);
DISPLAY 0.659574 (-7740 1510);
PAINT MONO (-7740 1510);
DISPLAY INVISIBLE (-7740 1510);
FORCEPROP 2 LAST CDS_LIB mstr_symbols
J 0
(-7750 1450);
PAINT MONO (-7750 1450);
DISPLAY INVISIBLE (-7750 1450);
FORCEPROP 1 LAST SIZE 1B
J 0
(-7675 1400);
DISPLAY 1.723404 (-7675 1400);
PAINT GREEN (-7675 1400);
DISPLAY INVISIBLE (-7675 1400);
FORCEPROP 2 LAST BOM_COST PROC_VRD_VCCIN_CPU0
J 0
(-8125 1525);
DISPLAY 1.446809 (-8125 1525);
PAINT MONO (-8125 1525);
DISPLAY INVISIBLE (-8125 1525);
FORCEPROP 2 LAST ROOM VDDQ_ABC_PWR_VR
J 0
(-8300 1525);
DISPLAY 1.936170 (-8300 1525);
PAINT ORANGE (-8300 1525);
DISPLAY INVISIBLE (-8300 1525);
FORCEPROP 1 LAST VOLTAGE 0
J 0
(-7750 1450);
PAINT SKYBLUE (-7750 1450);
DISPLAY INVISIBLE (-7750 1450);
FORCEPROP 1 LAST PATH I1
J 0
(-7675 1450);
DISPLAY 0.872340 (-7675 1450);
PAINT AQUA (-7675 1450);
DISPLAY INVISIBLE (-7675 1450);
FORCEPROP 1 LAST BODY_TYPE PLUMBING
J 0
(-7795 1407);
DISPLAY 0.340426 (-7795 1407);
PAINT GREEN (-7795 1407);
DISPLAY INVISIBLE (-7795 1407);
FORCEPROP 1 LAST HDL_POWER GND
J 0
(-7750 1600);
DISPLAY 1.723404 (-7750 1600);
PAINT GREEN (-7750 1600);
DISPLAY INVISIBLE (-7750 1600);
FORCEADD GND..1
(-7750 3350);
FORCEPROP 3 LASTPIN (-7750 3400) SIG_NAME GND\g
J 0
(-7740 3410);
DISPLAY 0.659574 (-7740 3410);
PAINT MONO (-7740 3410);
DISPLAY INVISIBLE (-7740 3410);
FORCEPROP 1 LAST PATH I11
J 0
(-7675 3350);
DISPLAY 0.872340 (-7675 3350);
PAINT AQUA (-7675 3350);
DISPLAY INVISIBLE (-7675 3350);
FORCEPROP 1 LAST VOLTAGE 0
J 0
(-7750 3350);
PAINT SKYBLUE (-7750 3350);
DISPLAY INVISIBLE (-7750 3350);
FORCEPROP 2 LAST ROOM VDDQ_ABC_PWR_VR
J 0
(-8300 3425);
DISPLAY 1.936170 (-8300 3425);
PAINT ORANGE (-8300 3425);
DISPLAY INVISIBLE (-8300 3425);
FORCEPROP 2 LAST BOM_COST PROC_VRD_VCCIN_CPU0
J 0
(-8125 3425);
DISPLAY 1.446809 (-8125 3425);
PAINT MONO (-8125 3425);
DISPLAY INVISIBLE (-8125 3425);
FORCEPROP 1 LAST SIZE 1B
J 0
(-7675 3300);
DISPLAY 1.723404 (-7675 3300);
PAINT GREEN (-7675 3300);
DISPLAY INVISIBLE (-7675 3300);
FORCEPROP 2 LAST CDS_LIB mstr_symbols
J 0
(-7750 3350);
PAINT MONO (-7750 3350);
DISPLAY INVISIBLE (-7750 3350);
FORCEPROP 1 LAST BODY_TYPE PLUMBING
J 0
(-7795 3307);
DISPLAY 0.340426 (-7795 3307);
PAINT GREEN (-7795 3307);
DISPLAY INVISIBLE (-7795 3307);
FORCEPROP 1 LAST HDL_POWER GND
J 0
(-7750 3500);
DISPLAY 1.723404 (-7750 3500);
PAINT GREEN (-7750 3500);
DISPLAY INVISIBLE (-7750 3500);
FORCEADD PVDDQ_GHJ..1
(-7750 4050);
FORCEPROP 3 LASTPIN (-7750 4000) SIG_NAME PVDDQ_GHJ\g
J 0
(-7740 4010);
DISPLAY 0.659574 (-7740 4010);
PAINT MONO (-7740 4010);
DISPLAY INVISIBLE (-7740 4010);
FORCEPROP 1 LAST HDL_POWER PVDDQ_GHJ
J 1
(-7750 4100);
DISPLAY 0.872340 (-7750 4100);
PAINT GREEN (-7750 4100);
DISPLAY INVISIBLE (-7750 4100);
FORCEPROP 1 LAST BODY_TYPE PLUMBING
J 0
(-7795 4007);
DISPLAY 0.340426 (-7795 4007);
PAINT GREEN (-7795 4007);
DISPLAY INVISIBLE (-7795 4007);
FORCEPROP 2 LAST CDS_LIB mstr_symbols
J 0
(-7750 4050);
PAINT MONO (-7750 4050);
DISPLAY INVISIBLE (-7750 4050);
FORCEPROP 1 LAST VOLTAGE 1.2V
J 0
(-7795 4007);
DISPLAY 0.340426 (-7795 4007);
PAINT SKYBLUE (-7795 4007);
DISPLAY INVISIBLE (-7795 4007);
FORCEPROP 1 LAST PATH I26
J 0
(-7700 4075);
DISPLAY 0.872340 (-7700 4075);
PAINT AQUA (-7700 4075);
DISPLAY INVISIBLE (-7700 4075);
FORCEADD GND..1
(-3800 1450);
FORCEPROP 3 LASTPIN (-3800 1500) SIG_NAME GND\g
J 0
(-3790 1510);
DISPLAY 0.659574 (-3790 1510);
PAINT MONO (-3790 1510);
DISPLAY INVISIBLE (-3790 1510);
FORCEPROP 1 LAST HDL_POWER GND
J 0
(-3800 1600);
DISPLAY 1.723404 (-3800 1600);
PAINT GREEN (-3800 1600);
DISPLAY INVISIBLE (-3800 1600);
FORCEPROP 1 LAST BODY_TYPE PLUMBING
J 0
(-3845 1407);
DISPLAY 0.340426 (-3845 1407);
PAINT GREEN (-3845 1407);
DISPLAY INVISIBLE (-3845 1407);
FORCEPROP 2 LAST CDS_LIB mstr_symbols
J 0
(-3800 1450);
PAINT MONO (-3800 1450);
DISPLAY INVISIBLE (-3800 1450);
FORCEPROP 1 LAST VOLTAGE 0
J 0
(-3800 1450);
PAINT SKYBLUE (-3800 1450);
DISPLAY INVISIBLE (-3800 1450);
FORCEPROP 2 LAST ROOM VDDQ_ABC_PWR_VR
J 0
(-4350 1525);
DISPLAY 1.936170 (-4350 1525);
PAINT ORANGE (-4350 1525);
DISPLAY INVISIBLE (-4350 1525);
FORCEPROP 2 LAST BOM_COST PROC_VRD_VCCIN_CPU0
J 0
(-4175 1525);
DISPLAY 1.446809 (-4175 1525);
PAINT MONO (-4175 1525);
DISPLAY INVISIBLE (-4175 1525);
FORCEPROP 1 LAST SIZE 1B
J 0
(-3725 1400);
DISPLAY 1.723404 (-3725 1400);
PAINT GREEN (-3725 1400);
DISPLAY INVISIBLE (-3725 1400);
FORCEPROP 1 LAST PATH I27
J 0
(-3725 1450);
DISPLAY 0.872340 (-3725 1450);
PAINT AQUA (-3725 1450);
DISPLAY INVISIBLE (-3725 1450);
FORCEADD PVDDQ_KLM..1
(-3800 2150);
FORCEPROP 3 LASTPIN (-3800 2100) SIG_NAME PVDDQ_KLM\g
J 0
(-3790 2110);
DISPLAY 0.659574 (-3790 2110);
PAINT MONO (-3790 2110);
DISPLAY INVISIBLE (-3790 2110);
FORCEPROP 1 LAST HDL_POWER PVDDQ_KLM
J 1
(-3800 2200);
DISPLAY 0.872340 (-3800 2200);
PAINT GREEN (-3800 2200);
DISPLAY INVISIBLE (-3800 2200);
FORCEPROP 1 LAST BODY_TYPE PLUMBING
J 0
(-3845 2107);
DISPLAY 0.340426 (-3845 2107);
PAINT GREEN (-3845 2107);
DISPLAY INVISIBLE (-3845 2107);
FORCEPROP 2 LAST CDS_LIB mstr_symbols
J 0
(-3800 2150);
PAINT MONO (-3800 2150);
DISPLAY INVISIBLE (-3800 2150);
FORCEPROP 2 LAST BOM_COST VDDQ_KLM_PWR_VR
J 0
(-3800 2250);
DISPLAY 1.446809 (-3800 2250);
PAINT MONO (-3800 2250);
DISPLAY INVISIBLE (-3800 2250);
FORCEPROP 2 LAST ROOM VDDQ_KLM_PWR_VR
J 0
(-3800 2250);
DISPLAY 1.936170 (-3800 2250);
PAINT ORANGE (-3800 2250);
DISPLAY INVISIBLE (-3800 2250);
FORCEPROP 1 LAST VOLTAGE 1.2V
J 0
(-3845 2107);
DISPLAY 0.340426 (-3845 2107);
PAINT SKYBLUE (-3845 2107);
DISPLAY INVISIBLE (-3845 2107);
FORCEPROP 1 LAST PATH I29
J 0
(-3750 2175);
DISPLAY 0.872340 (-3750 2175);
PAINT AQUA (-3750 2175);
DISPLAY INVISIBLE (-3750 2175);
FORCEADD PVDDQ_GHJ..1
(-7750 2150);
FORCEPROP 3 LASTPIN (-7750 2100) SIG_NAME PVDDQ_GHJ\g
J 0
(-7740 2110);
DISPLAY 0.659574 (-7740 2110);
PAINT MONO (-7740 2110);
DISPLAY INVISIBLE (-7740 2110);
FORCEPROP 2 LAST CDS_LIB mstr_symbols
J 0
(-7750 2150);
PAINT MONO (-7750 2150);
DISPLAY INVISIBLE (-7750 2150);
FORCEPROP 1 LAST VOLTAGE 1.2V
J 0
(-7795 2107);
DISPLAY 0.340426 (-7795 2107);
PAINT SKYBLUE (-7795 2107);
DISPLAY INVISIBLE (-7795 2107);
FORCEPROP 1 LAST PATH I3
J 0
(-7700 2175);
DISPLAY 0.872340 (-7700 2175);
PAINT AQUA (-7700 2175);
DISPLAY INVISIBLE (-7700 2175);
FORCEPROP 1 LAST BODY_TYPE PLUMBING
J 0
(-7795 2107);
DISPLAY 0.340426 (-7795 2107);
PAINT GREEN (-7795 2107);
DISPLAY INVISIBLE (-7795 2107);
FORCEPROP 1 LAST HDL_POWER PVDDQ_GHJ
J 1
(-7750 2200);
DISPLAY 0.872340 (-7750 2200);
PAINT GREEN (-7750 2200);
DISPLAY INVISIBLE (-7750 2200);
FORCEADD GND..1
(-3800 2400);
FORCEPROP 3 LASTPIN (-3800 2450) SIG_NAME GND\g
J 0
(-3790 2460);
DISPLAY 0.659574 (-3790 2460);
PAINT MONO (-3790 2460);
DISPLAY INVISIBLE (-3790 2460);
FORCEPROP 1 LAST PATH I34
J 0
(-3725 2400);
DISPLAY 0.872340 (-3725 2400);
PAINT AQUA (-3725 2400);
DISPLAY INVISIBLE (-3725 2400);
FORCEPROP 1 LAST VOLTAGE 0
J 0
(-3800 2400);
PAINT SKYBLUE (-3800 2400);
DISPLAY INVISIBLE (-3800 2400);
FORCEPROP 2 LAST ROOM VDDQ_ABC_PWR_VR
J 0
(-4350 2475);
DISPLAY 1.936170 (-4350 2475);
PAINT ORANGE (-4350 2475);
DISPLAY INVISIBLE (-4350 2475);
FORCEPROP 2 LAST BOM_COST PROC_VRD_VCCIN_CPU0
J 0
(-4175 2475);
DISPLAY 1.446809 (-4175 2475);
PAINT MONO (-4175 2475);
DISPLAY INVISIBLE (-4175 2475);
FORCEPROP 1 LAST SIZE 1B
J 0
(-3725 2350);
DISPLAY 1.723404 (-3725 2350);
PAINT GREEN (-3725 2350);
DISPLAY INVISIBLE (-3725 2350);
FORCEPROP 2 LAST CDS_LIB mstr_symbols
J 0
(-3800 2400);
PAINT MONO (-3800 2400);
DISPLAY INVISIBLE (-3800 2400);
FORCEPROP 1 LAST BODY_TYPE PLUMBING
J 0
(-3845 2357);
DISPLAY 0.340426 (-3845 2357);
PAINT GREEN (-3845 2357);
DISPLAY INVISIBLE (-3845 2357);
FORCEPROP 1 LAST HDL_POWER GND
J 0
(-3800 2550);
DISPLAY 1.723404 (-3800 2550);
PAINT GREEN (-3800 2550);
DISPLAY INVISIBLE (-3800 2550);
FORCEADD PVDDQ_KLM..1
(-3800 3100);
FORCEPROP 3 LASTPIN (-3800 3050) SIG_NAME PVDDQ_KLM\g
J 0
(-3790 3060);
DISPLAY 0.659574 (-3790 3060);
PAINT MONO (-3790 3060);
DISPLAY INVISIBLE (-3790 3060);
FORCEPROP 1 LAST PATH I36
J 0
(-3750 3125);
DISPLAY 0.872340 (-3750 3125);
PAINT AQUA (-3750 3125);
DISPLAY INVISIBLE (-3750 3125);
FORCEPROP 1 LAST VOLTAGE 1.2V
J 0
(-3845 3057);
DISPLAY 0.340426 (-3845 3057);
PAINT SKYBLUE (-3845 3057);
DISPLAY INVISIBLE (-3845 3057);
FORCEPROP 2 LAST ROOM VDDQ_KLM_PWR_VR
J 0
(-3800 3200);
DISPLAY 1.936170 (-3800 3200);
PAINT ORANGE (-3800 3200);
DISPLAY INVISIBLE (-3800 3200);
FORCEPROP 2 LAST BOM_COST VDDQ_KLM_PWR_VR
J 0
(-3800 3200);
DISPLAY 1.446809 (-3800 3200);
PAINT MONO (-3800 3200);
DISPLAY INVISIBLE (-3800 3200);
FORCEPROP 2 LAST CDS_LIB mstr_symbols
J 0
(-3800 3100);
PAINT MONO (-3800 3100);
DISPLAY INVISIBLE (-3800 3100);
FORCEPROP 1 LAST BODY_TYPE PLUMBING
J 0
(-3845 3057);
DISPLAY 0.340426 (-3845 3057);
PAINT GREEN (-3845 3057);
DISPLAY INVISIBLE (-3845 3057);
FORCEPROP 1 LAST HDL_POWER PVDDQ_KLM
J 1
(-3800 3150);
DISPLAY 0.872340 (-3800 3150);
PAINT GREEN (-3800 3150);
DISPLAY INVISIBLE (-3800 3150);
FORCEADD GND..1
(-3800 3350);
FORCEPROP 3 LASTPIN (-3800 3400) SIG_NAME GND\g
J 0
(-3790 3410);
DISPLAY 0.659574 (-3790 3410);
PAINT MONO (-3790 3410);
DISPLAY INVISIBLE (-3790 3410);
FORCEPROP 1 LAST HDL_POWER GND
J 0
(-3800 3500);
DISPLAY 1.723404 (-3800 3500);
PAINT GREEN (-3800 3500);
DISPLAY INVISIBLE (-3800 3500);
FORCEPROP 1 LAST BODY_TYPE PLUMBING
J 0
(-3845 3307);
DISPLAY 0.340426 (-3845 3307);
PAINT GREEN (-3845 3307);
DISPLAY INVISIBLE (-3845 3307);
FORCEPROP 2 LAST CDS_LIB mstr_symbols
J 0
(-3800 3350);
PAINT MONO (-3800 3350);
DISPLAY INVISIBLE (-3800 3350);
FORCEPROP 1 LAST SIZE 1B
J 0
(-3725 3300);
DISPLAY 1.723404 (-3725 3300);
PAINT GREEN (-3725 3300);
DISPLAY INVISIBLE (-3725 3300);
FORCEPROP 2 LAST BOM_COST PROC_VRD_VCCIN_CPU0
J 0
(-4175 3425);
DISPLAY 1.446809 (-4175 3425);
PAINT MONO (-4175 3425);
DISPLAY INVISIBLE (-4175 3425);
FORCEPROP 2 LAST ROOM VDDQ_ABC_PWR_VR
J 0
(-4350 3425);
DISPLAY 1.936170 (-4350 3425);
PAINT ORANGE (-4350 3425);
DISPLAY INVISIBLE (-4350 3425);
FORCEPROP 1 LAST VOLTAGE 0
J 0
(-3800 3350);
PAINT SKYBLUE (-3800 3350);
DISPLAY INVISIBLE (-3800 3350);
FORCEPROP 1 LAST PATH I38
J 0
(-3725 3350);
DISPLAY 0.872340 (-3725 3350);
PAINT AQUA (-3725 3350);
DISPLAY INVISIBLE (-3725 3350);
FORCEADD PVDDQ_KLM..1
(-3800 4050);
FORCEPROP 3 LASTPIN (-3800 4000) SIG_NAME PVDDQ_KLM\g
J 0
(-3790 4010);
DISPLAY 0.659574 (-3790 4010);
PAINT MONO (-3790 4010);
DISPLAY INVISIBLE (-3790 4010);
FORCEPROP 1 LAST HDL_POWER PVDDQ_KLM
J 1
(-3800 4100);
DISPLAY 0.872340 (-3800 4100);
PAINT GREEN (-3800 4100);
DISPLAY INVISIBLE (-3800 4100);
FORCEPROP 1 LAST BODY_TYPE PLUMBING
J 0
(-3845 4007);
DISPLAY 0.340426 (-3845 4007);
PAINT GREEN (-3845 4007);
DISPLAY INVISIBLE (-3845 4007);
FORCEPROP 2 LAST CDS_LIB mstr_symbols
J 0
(-3800 4050);
PAINT MONO (-3800 4050);
DISPLAY INVISIBLE (-3800 4050);
FORCEPROP 2 LAST BOM_COST VDDQ_KLM_PWR_VR
J 0
(-3800 4150);
DISPLAY 1.446809 (-3800 4150);
PAINT MONO (-3800 4150);
DISPLAY INVISIBLE (-3800 4150);
FORCEPROP 2 LAST ROOM VDDQ_KLM_PWR_VR
J 0
(-3800 4150);
DISPLAY 1.936170 (-3800 4150);
PAINT ORANGE (-3800 4150);
DISPLAY INVISIBLE (-3800 4150);
FORCEPROP 1 LAST VOLTAGE 1.2V
J 0
(-3845 4007);
DISPLAY 0.340426 (-3845 4007);
PAINT SKYBLUE (-3845 4007);
DISPLAY INVISIBLE (-3845 4007);
FORCEPROP 1 LAST PATH I51
J 0
(-3750 4075);
DISPLAY 0.872340 (-3750 4075);
PAINT AQUA (-3750 4075);
DISPLAY INVISIBLE (-3750 4075);
FORCEADD CAP_A..1
(-7750 2800);
FORCEPROP 1 LAST MATERIAL X6S
J 0
(-7700 2700);
DISPLAY 0.617021 (-7700 2700);
PAINT SKYBLUE (-7700 2700);
FORCEPROP 1 LAST LOCATION C5G79
J 0
(-7700 2900);
DISPLAY 0.617021 (-7700 2900);
PAINT AQUA (-7700 2900);
FORCEPROP 1 LAST VALUE 22.0UF
J 0
(-7700 2850);
DISPLAY 0.617021 (-7700 2850);
PAINT SKYBLUE (-7700 2850);
FORCEPROP 1 LAST VOLTAGE 4V
J 0
(-7700 2800);
DISPLAY 0.617021 (-7700 2800);
PAINT SKYBLUE (-7700 2800);
FORCEPROP 1 LAST TOLERANCE 20%
J 0
(-7700 2750);
DISPLAY 0.617021 (-7700 2750);
PAINT SKYBLUE (-7700 2750);
FORCEPROP 1 LAST PACK_TYPE 0603V
J 0
(-7700 2600);
DISPLAY 0.617021 (-7700 2600);
PAINT SKYBLUE (-7700 2600);
FORCEPROP 1 LASTPIN (-7750 2700) $PN 2
J 0
(-7740 2680);
DISPLAY 0.787234 (-7740 2680);
PAINT ORANGE (-7740 2680);
FORCEPROP 1 LASTPIN (-7750 2900) $PN 1
J 0
(-7740 2880);
DISPLAY 0.787234 (-7740 2880);
PAINT ORANGE (-7740 2880);
FORCEPROP 1 LAST PART_NUMBER E15431-004
J 0
(-7700 2650);
DISPLAY 0.617021 (-7700 2650);
PAINT BLUE (-7700 2650);
FORCEPROP 0 LAST GROUP PWR_MLCC_CAP
J 0
(-7694 2512);
DISPLAY 0.638298 (-7694 2512);
PAINT BROWN (-7694 2512);
DISPLAY BOTH (-7694 2512);
FORCEPROP 0 LAST BOM_DS NOPOP
J 0
(-7700 2550);
DISPLAY 0.638298 (-7700 2550);
PAINT BROWN (-7700 2550);
DISPLAY BOTH (-7700 2550);
FORCEPROP 2 LAST CDS_LIB dev_discrete
J 0
(-7750 2800);
PAINT MONO (-7750 2800);
DISPLAY INVISIBLE (-7750 2800);
FORCEPROP 1 LAST PATH I53
J 0
(-7700 2950);
DISPLAY 0.978723 (-7700 2950);
PAINT WHITE (-7700 2950);
DISPLAY INVISIBLE (-7700 2950);
FORCEPROP 0 LAST ROOM PVDDQ_KLM
J 0
(-7700 3000);
DISPLAY 1.021277 (-7700 3000);
PAINT ORANGE (-7700 3000);
DISPLAY INVISIBLE (-7700 3000);
FORCEPROP 0 LAST SEC 1
J 0
(-7700 2950);
DISPLAY 0.680851 (-7700 2950);
PAINT MONO (-7700 2950);
DISPLAY INVISIBLE (-7700 2950);
FORCEPROP 2 LAST SEC_TYPE 0603V
J 0
(-7700 3000);
DISPLAY 1.021277 (-7700 3000);
PAINT ORANGE (-7700 3000);
DISPLAY INVISIBLE (-7700 3000);
FORCEADD CAP_A..1
(-4550 2775);
FORCEPROP 1 LAST MATERIAL X6S
J 0
(-4500 2675);
DISPLAY 0.617021 (-4500 2675);
PAINT SKYBLUE (-4500 2675);
FORCEPROP 1 LAST TOLERANCE 20%
J 0
(-4500 2725);
DISPLAY 0.617021 (-4500 2725);
PAINT SKYBLUE (-4500 2725);
FORCEPROP 1 LAST PACK_TYPE 0603V
J 0
(-4500 2575);
DISPLAY 0.617021 (-4500 2575);
PAINT SKYBLUE (-4500 2575);
FORCEPROP 1 LASTPIN (-4550 2675) $PN 2
J 0
(-4540 2655);
DISPLAY 0.787234 (-4540 2655);
PAINT ORANGE (-4540 2655);
FORCEPROP 1 LAST LOCATION C5G87
J 0
(-4500 2875);
DISPLAY 0.617021 (-4500 2875);
PAINT AQUA (-4500 2875);
FORCEPROP 1 LASTPIN (-4550 2875) $PN 1
J 0
(-4540 2855);
DISPLAY 0.787234 (-4540 2855);
PAINT ORANGE (-4540 2855);
FORCEPROP 1 LAST VOLTAGE 4V
J 0
(-4500 2775);
DISPLAY 0.617021 (-4500 2775);
PAINT SKYBLUE (-4500 2775);
FORCEPROP 1 LAST VALUE 22.0UF
J 0
(-4500 2825);
DISPLAY 0.617021 (-4500 2825);
PAINT SKYBLUE (-4500 2825);
FORCEPROP 1 LAST PART_NUMBER E15431-004
J 0
(-4500 2625);
DISPLAY 0.617021 (-4500 2625);
PAINT BLUE (-4500 2625);
FORCEPROP 0 LAST GROUP PWR_MLCC_CAP
J 0
(-4494 2412);
DISPLAY 0.638298 (-4494 2412);
PAINT BROWN (-4494 2412);
DISPLAY BOTH (-4494 2412);
FORCEPROP 0 LAST BOM_DS NOPOP
J 0
(-4500 2525);
DISPLAY 0.638298 (-4500 2525);
PAINT BROWN (-4500 2525);
DISPLAY BOTH (-4500 2525);
FORCEPROP 2 LAST CDS_LIB dev_discrete
J 0
(-4550 2775);
PAINT MONO (-4550 2775);
DISPLAY INVISIBLE (-4550 2775);
FORCEPROP 1 LAST PATH I54
J 0
(-4500 2925);
DISPLAY 0.978723 (-4500 2925);
PAINT WHITE (-4500 2925);
DISPLAY INVISIBLE (-4500 2925);
FORCEPROP 0 LAST ROOM PVDDQ_KLM
J 0
(-4500 2975);
DISPLAY 1.021277 (-4500 2975);
PAINT ORANGE (-4500 2975);
DISPLAY INVISIBLE (-4500 2975);
FORCEPROP 0 LAST SEC 1
J 0
(-4500 2925);
DISPLAY 0.680851 (-4500 2925);
PAINT MONO (-4500 2925);
DISPLAY INVISIBLE (-4500 2925);
FORCEPROP 2 LAST SEC_TYPE 0603V
J 0
(-4500 2975);
DISPLAY 1.021277 (-4500 2975);
PAINT ORANGE (-4500 2975);
DISPLAY INVISIBLE (-4500 2975);
FORCEADD CAP_A..1
(-4950 2800);
FORCEPROP 1 LAST MATERIAL X6S
J 0
(-4900 2700);
DISPLAY 0.617021 (-4900 2700);
PAINT SKYBLUE (-4900 2700);
FORCEPROP 1 LAST LOCATION C5G86
J 0
(-4900 2900);
DISPLAY 0.617021 (-4900 2900);
PAINT AQUA (-4900 2900);
FORCEPROP 1 LAST PACK_TYPE 0603V
J 0
(-4900 2600);
DISPLAY 0.617021 (-4900 2600);
PAINT SKYBLUE (-4900 2600);
FORCEPROP 1 LASTPIN (-4950 2700) $PN 2
J 0
(-4940 2680);
DISPLAY 0.787234 (-4940 2680);
PAINT ORANGE (-4940 2680);
FORCEPROP 1 LAST VOLTAGE 4V
J 0
(-4900 2800);
DISPLAY 0.617021 (-4900 2800);
PAINT SKYBLUE (-4900 2800);
FORCEPROP 1 LAST TOLERANCE 20%
J 0
(-4900 2750);
DISPLAY 0.617021 (-4900 2750);
PAINT SKYBLUE (-4900 2750);
FORCEPROP 1 LAST VALUE 22.0UF
J 0
(-4900 2850);
DISPLAY 0.617021 (-4900 2850);
PAINT SKYBLUE (-4900 2850);
FORCEPROP 1 LASTPIN (-4950 2900) $PN 1
J 0
(-4940 2880);
DISPLAY 0.787234 (-4940 2880);
PAINT ORANGE (-4940 2880);
FORCEPROP 0 LAST GROUP PWR_MLCC_CAP
J 0
(-4894 2462);
DISPLAY 0.638298 (-4894 2462);
PAINT BROWN (-4894 2462);
DISPLAY BOTH (-4894 2462);
FORCEPROP 1 LAST PART_NUMBER E15431-004
J 0
(-4900 2650);
DISPLAY 0.617021 (-4900 2650);
PAINT BLUE (-4900 2650);
FORCEPROP 0 LAST BOM_DS NOPOP
J 0
(-4900 2550);
DISPLAY 0.638298 (-4900 2550);
PAINT BROWN (-4900 2550);
DISPLAY BOTH (-4900 2550);
FORCEPROP 2 LAST CDS_LIB dev_discrete
J 0
(-4950 2800);
PAINT MONO (-4950 2800);
DISPLAY INVISIBLE (-4950 2800);
FORCEPROP 1 LAST PATH I55
J 0
(-4900 2950);
DISPLAY 0.978723 (-4900 2950);
PAINT WHITE (-4900 2950);
DISPLAY INVISIBLE (-4900 2950);
FORCEPROP 0 LAST ROOM PVDDQ_KLM
J 0
(-4900 3000);
DISPLAY 1.021277 (-4900 3000);
PAINT ORANGE (-4900 3000);
DISPLAY INVISIBLE (-4900 3000);
FORCEPROP 0 LAST SEC 1
J 0
(-4900 2950);
DISPLAY 0.680851 (-4900 2950);
PAINT MONO (-4900 2950);
DISPLAY INVISIBLE (-4900 2950);
FORCEPROP 2 LAST SEC_TYPE 0603V
J 0
(-4900 3000);
DISPLAY 1.021277 (-4900 3000);
PAINT ORANGE (-4900 3000);
DISPLAY INVISIBLE (-4900 3000);
FORCEADD CAP_A..1
(-5350 2800);
FORCEPROP 1 LAST VALUE 22.0UF
J 0
(-5300 2850);
DISPLAY 0.617021 (-5300 2850);
PAINT SKYBLUE (-5300 2850);
FORCEPROP 1 LAST VOLTAGE 4V
J 0
(-5300 2800);
DISPLAY 0.617021 (-5300 2800);
PAINT SKYBLUE (-5300 2800);
FORCEPROP 1 LAST PACK_TYPE 0603V
J 0
(-5300 2600);
DISPLAY 0.617021 (-5300 2600);
PAINT SKYBLUE (-5300 2600);
FORCEPROP 1 LASTPIN (-5350 2700) $PN 2
J 0
(-5340 2680);
DISPLAY 0.787234 (-5340 2680);
PAINT ORANGE (-5340 2680);
FORCEPROP 1 LASTPIN (-5350 2900) $PN 1
J 0
(-5340 2880);
DISPLAY 0.787234 (-5340 2880);
PAINT ORANGE (-5340 2880);
FORCEPROP 1 LAST TOLERANCE 20%
J 0
(-5300 2750);
DISPLAY 0.617021 (-5300 2750);
PAINT SKYBLUE (-5300 2750);
FORCEPROP 1 LAST LOCATION C5G85
J 0
(-5300 2900);
DISPLAY 0.617021 (-5300 2900);
PAINT AQUA (-5300 2900);
FORCEPROP 0 LAST GROUP PWR_MLCC_CAP
J 0
(-5294 2512);
DISPLAY 0.638298 (-5294 2512);
PAINT BROWN (-5294 2512);
DISPLAY BOTH (-5294 2512);
FORCEPROP 1 LAST MATERIAL X6S
J 0
(-5300 2700);
DISPLAY 0.617021 (-5300 2700);
PAINT SKYBLUE (-5300 2700);
FORCEPROP 1 LAST PART_NUMBER E15431-004
J 0
(-5300 2650);
DISPLAY 0.617021 (-5300 2650);
PAINT BLUE (-5300 2650);
FORCEPROP 0 LAST BOM_DS NOPOP
J 0
(-5300 2550);
DISPLAY 0.638298 (-5300 2550);
PAINT BROWN (-5300 2550);
DISPLAY BOTH (-5300 2550);
FORCEPROP 2 LAST CDS_LIB dev_discrete
J 0
(-5350 2800);
PAINT MONO (-5350 2800);
DISPLAY INVISIBLE (-5350 2800);
FORCEPROP 1 LAST PATH I56
J 0
(-5300 2950);
DISPLAY 0.978723 (-5300 2950);
PAINT WHITE (-5300 2950);
DISPLAY INVISIBLE (-5300 2950);
FORCEPROP 0 LAST ROOM PVDDQ_KLM
J 0
(-5300 3000);
DISPLAY 1.021277 (-5300 3000);
PAINT ORANGE (-5300 3000);
DISPLAY INVISIBLE (-5300 3000);
FORCEPROP 0 LAST SEC 1
J 0
(-5300 2950);
DISPLAY 0.680851 (-5300 2950);
PAINT MONO (-5300 2950);
DISPLAY INVISIBLE (-5300 2950);
FORCEPROP 2 LAST SEC_TYPE 0603V
J 0
(-5300 3000);
DISPLAY 1.021277 (-5300 3000);
PAINT ORANGE (-5300 3000);
DISPLAY INVISIBLE (-5300 3000);
FORCEADD CAP_A..1
(-5750 2800);
FORCEPROP 1 LAST LOCATION C5G84
J 0
(-5700 2900);
DISPLAY 0.617021 (-5700 2900);
PAINT AQUA (-5700 2900);
FORCEPROP 1 LAST VALUE 22.0UF
J 0
(-5700 2850);
DISPLAY 0.617021 (-5700 2850);
PAINT SKYBLUE (-5700 2850);
FORCEPROP 1 LAST PACK_TYPE 0603V
J 0
(-5700 2600);
DISPLAY 0.617021 (-5700 2600);
PAINT SKYBLUE (-5700 2600);
FORCEPROP 1 LASTPIN (-5750 2700) $PN 2
J 0
(-5740 2680);
DISPLAY 0.787234 (-5740 2680);
PAINT ORANGE (-5740 2680);
FORCEPROP 1 LASTPIN (-5750 2900) $PN 1
J 0
(-5740 2880);
DISPLAY 0.787234 (-5740 2880);
PAINT ORANGE (-5740 2880);
FORCEPROP 1 LAST VOLTAGE 4V
J 0
(-5700 2800);
DISPLAY 0.617021 (-5700 2800);
PAINT SKYBLUE (-5700 2800);
FORCEPROP 1 LAST TOLERANCE 20%
J 0
(-5700 2750);
DISPLAY 0.617021 (-5700 2750);
PAINT SKYBLUE (-5700 2750);
FORCEPROP 0 LAST GROUP PWR_MLCC_CAP
J 0
(-5694 2462);
DISPLAY 0.638298 (-5694 2462);
PAINT BROWN (-5694 2462);
DISPLAY BOTH (-5694 2462);
FORCEPROP 1 LAST MATERIAL X6S
J 0
(-5700 2700);
DISPLAY 0.617021 (-5700 2700);
PAINT SKYBLUE (-5700 2700);
FORCEPROP 1 LAST PART_NUMBER E15431-004
J 0
(-5700 2650);
DISPLAY 0.617021 (-5700 2650);
PAINT BLUE (-5700 2650);
FORCEPROP 0 LAST BOM_DS NOPOP
J 0
(-5700 2550);
DISPLAY 0.638298 (-5700 2550);
PAINT BROWN (-5700 2550);
DISPLAY BOTH (-5700 2550);
FORCEPROP 2 LAST CDS_LIB dev_discrete
J 0
(-5750 2800);
PAINT MONO (-5750 2800);
DISPLAY INVISIBLE (-5750 2800);
FORCEPROP 1 LAST PATH I57
J 0
(-5700 2950);
DISPLAY 0.978723 (-5700 2950);
PAINT WHITE (-5700 2950);
DISPLAY INVISIBLE (-5700 2950);
FORCEPROP 0 LAST ROOM PVDDQ_KLM
J 0
(-5700 3000);
DISPLAY 1.021277 (-5700 3000);
PAINT ORANGE (-5700 3000);
DISPLAY INVISIBLE (-5700 3000);
FORCEPROP 0 LAST SEC 1
J 0
(-5700 2950);
DISPLAY 0.680851 (-5700 2950);
PAINT MONO (-5700 2950);
DISPLAY INVISIBLE (-5700 2950);
FORCEPROP 2 LAST SEC_TYPE 0603V
J 0
(-5700 3000);
DISPLAY 1.021277 (-5700 3000);
PAINT ORANGE (-5700 3000);
DISPLAY INVISIBLE (-5700 3000);
FORCEADD CAP_A..1
(-6150 2800);
FORCEPROP 1 LAST MATERIAL X6S
J 0
(-6100 2700);
DISPLAY 0.617021 (-6100 2700);
PAINT SKYBLUE (-6100 2700);
FORCEPROP 1 LAST PACK_TYPE 0603V
J 0
(-6100 2600);
DISPLAY 0.617021 (-6100 2600);
PAINT SKYBLUE (-6100 2600);
FORCEPROP 1 LASTPIN (-6150 2700) $PN 2
J 0
(-6140 2680);
DISPLAY 0.787234 (-6140 2680);
PAINT ORANGE (-6140 2680);
FORCEPROP 1 LASTPIN (-6150 2900) $PN 1
J 0
(-6140 2880);
DISPLAY 0.787234 (-6140 2880);
PAINT ORANGE (-6140 2880);
FORCEPROP 1 LAST PART_NUMBER E15431-004
J 0
(-6100 2650);
DISPLAY 0.617021 (-6100 2650);
PAINT BLUE (-6100 2650);
FORCEPROP 1 LAST TOLERANCE 20%
J 0
(-6100 2750);
DISPLAY 0.617021 (-6100 2750);
PAINT SKYBLUE (-6100 2750);
FORCEPROP 1 LAST LOCATION C5G83
J 0
(-6100 2900);
DISPLAY 0.617021 (-6100 2900);
PAINT AQUA (-6100 2900);
FORCEPROP 0 LAST GROUP PWR_MLCC_CAP
J 0
(-6094 2512);
DISPLAY 0.638298 (-6094 2512);
PAINT BROWN (-6094 2512);
DISPLAY BOTH (-6094 2512);
FORCEPROP 1 LAST VOLTAGE 4V
J 0
(-6100 2800);
DISPLAY 0.617021 (-6100 2800);
PAINT SKYBLUE (-6100 2800);
FORCEPROP 1 LAST VALUE 22.0UF
J 0
(-6100 2850);
DISPLAY 0.617021 (-6100 2850);
PAINT SKYBLUE (-6100 2850);
FORCEPROP 0 LAST BOM_DS NOPOP
J 0
(-6100 2550);
DISPLAY 0.638298 (-6100 2550);
PAINT BROWN (-6100 2550);
DISPLAY BOTH (-6100 2550);
FORCEPROP 2 LAST CDS_LIB dev_discrete
J 0
(-6150 2800);
PAINT MONO (-6150 2800);
DISPLAY INVISIBLE (-6150 2800);
FORCEPROP 1 LAST PATH I58
J 0
(-6100 2950);
DISPLAY 0.978723 (-6100 2950);
PAINT WHITE (-6100 2950);
DISPLAY INVISIBLE (-6100 2950);
FORCEPROP 0 LAST ROOM PVDDQ_KLM
J 0
(-6100 3000);
DISPLAY 1.021277 (-6100 3000);
PAINT ORANGE (-6100 3000);
DISPLAY INVISIBLE (-6100 3000);
FORCEPROP 0 LAST SEC 1
J 0
(-6100 2950);
DISPLAY 0.680851 (-6100 2950);
PAINT MONO (-6100 2950);
DISPLAY INVISIBLE (-6100 2950);
FORCEPROP 2 LAST SEC_TYPE 0603V
J 0
(-6100 3000);
DISPLAY 1.021277 (-6100 3000);
PAINT ORANGE (-6100 3000);
DISPLAY INVISIBLE (-6100 3000);
FORCEADD CAP_A..1
(-6550 2800);
FORCEPROP 1 LAST MATERIAL X6S
J 0
(-6500 2700);
DISPLAY 0.617021 (-6500 2700);
PAINT SKYBLUE (-6500 2700);
FORCEPROP 1 LASTPIN (-6550 2700) $PN 2
J 0
(-6540 2680);
DISPLAY 0.787234 (-6540 2680);
PAINT ORANGE (-6540 2680);
FORCEPROP 1 LASTPIN (-6550 2900) $PN 1
J 0
(-6540 2880);
DISPLAY 0.787234 (-6540 2880);
PAINT ORANGE (-6540 2880);
FORCEPROP 1 LAST LOCATION C5G82
J 0
(-6500 2900);
DISPLAY 0.617021 (-6500 2900);
PAINT AQUA (-6500 2900);
FORCEPROP 1 LAST VALUE 22.0UF
J 0
(-6500 2850);
DISPLAY 0.617021 (-6500 2850);
PAINT SKYBLUE (-6500 2850);
FORCEPROP 1 LAST VOLTAGE 4V
J 0
(-6500 2800);
DISPLAY 0.617021 (-6500 2800);
PAINT SKYBLUE (-6500 2800);
FORCEPROP 1 LAST TOLERANCE 20%
J 0
(-6500 2750);
DISPLAY 0.617021 (-6500 2750);
PAINT SKYBLUE (-6500 2750);
FORCEPROP 1 LAST PACK_TYPE 0603V
J 0
(-6500 2600);
DISPLAY 0.617021 (-6500 2600);
PAINT SKYBLUE (-6500 2600);
FORCEPROP 0 LAST GROUP PWR_MLCC_CAP
J 0
(-6494 2462);
DISPLAY 0.638298 (-6494 2462);
PAINT BROWN (-6494 2462);
DISPLAY BOTH (-6494 2462);
FORCEPROP 1 LAST PART_NUMBER E15431-004
J 0
(-6500 2650);
DISPLAY 0.617021 (-6500 2650);
PAINT BLUE (-6500 2650);
FORCEPROP 0 LAST BOM_DS NOPOP
J 0
(-6500 2550);
DISPLAY 0.638298 (-6500 2550);
PAINT BROWN (-6500 2550);
DISPLAY BOTH (-6500 2550);
FORCEPROP 2 LAST CDS_LIB dev_discrete
J 0
(-6550 2800);
PAINT MONO (-6550 2800);
DISPLAY INVISIBLE (-6550 2800);
FORCEPROP 1 LAST PATH I59
J 0
(-6500 2950);
DISPLAY 0.978723 (-6500 2950);
PAINT WHITE (-6500 2950);
DISPLAY INVISIBLE (-6500 2950);
FORCEPROP 0 LAST ROOM PVDDQ_KLM
J 0
(-6500 3000);
DISPLAY 1.021277 (-6500 3000);
PAINT ORANGE (-6500 3000);
DISPLAY INVISIBLE (-6500 3000);
FORCEPROP 0 LAST SEC 1
J 0
(-6500 2950);
DISPLAY 0.680851 (-6500 2950);
PAINT MONO (-6500 2950);
DISPLAY INVISIBLE (-6500 2950);
FORCEPROP 2 LAST SEC_TYPE 0603V
J 0
(-6500 3000);
DISPLAY 1.021277 (-6500 3000);
PAINT ORANGE (-6500 3000);
DISPLAY INVISIBLE (-6500 3000);
FORCEADD GND..1
(-7750 2400);
FORCEPROP 3 LASTPIN (-7750 2450) SIG_NAME GND\g
J 0
(-7740 2460);
DISPLAY 0.659574 (-7740 2460);
PAINT MONO (-7740 2460);
DISPLAY INVISIBLE (-7740 2460);
FORCEPROP 1 LAST HDL_POWER GND
J 0
(-7750 2550);
DISPLAY 1.723404 (-7750 2550);
PAINT GREEN (-7750 2550);
DISPLAY INVISIBLE (-7750 2550);
FORCEPROP 1 LAST BODY_TYPE PLUMBING
J 0
(-7795 2357);
DISPLAY 0.340426 (-7795 2357);
PAINT GREEN (-7795 2357);
DISPLAY INVISIBLE (-7795 2357);
FORCEPROP 2 LAST CDS_LIB mstr_symbols
J 0
(-7750 2400);
PAINT MONO (-7750 2400);
DISPLAY INVISIBLE (-7750 2400);
FORCEPROP 1 LAST SIZE 1B
J 0
(-7675 2350);
DISPLAY 1.723404 (-7675 2350);
PAINT GREEN (-7675 2350);
DISPLAY INVISIBLE (-7675 2350);
FORCEPROP 2 LAST BOM_COST PROC_VRD_VCCIN_CPU0
J 0
(-8125 2475);
DISPLAY 1.446809 (-8125 2475);
PAINT MONO (-8125 2475);
DISPLAY INVISIBLE (-8125 2475);
FORCEPROP 2 LAST ROOM VDDQ_ABC_PWR_VR
J 0
(-8300 2475);
DISPLAY 1.936170 (-8300 2475);
PAINT ORANGE (-8300 2475);
DISPLAY INVISIBLE (-8300 2475);
FORCEPROP 1 LAST VOLTAGE 0
J 0
(-7750 2400);
PAINT SKYBLUE (-7750 2400);
DISPLAY INVISIBLE (-7750 2400);
FORCEPROP 1 LAST PATH I6
J 0
(-7675 2400);
DISPLAY 0.872340 (-7675 2400);
PAINT AQUA (-7675 2400);
DISPLAY INVISIBLE (-7675 2400);
FORCEADD CAP_A..1
(-6950 2800);
FORCEPROP 1 LAST PACK_TYPE 0603V
J 0
(-6900 2600);
DISPLAY 0.617021 (-6900 2600);
PAINT SKYBLUE (-6900 2600);
FORCEPROP 1 LASTPIN (-6950 2700) $PN 2
J 0
(-6940 2680);
DISPLAY 0.787234 (-6940 2680);
PAINT ORANGE (-6940 2680);
FORCEPROP 1 LASTPIN (-6950 2900) $PN 1
J 0
(-6940 2880);
DISPLAY 0.787234 (-6940 2880);
PAINT ORANGE (-6940 2880);
FORCEPROP 1 LAST PART_NUMBER E15431-004
J 0
(-6900 2650);
DISPLAY 0.617021 (-6900 2650);
PAINT BLUE (-6900 2650);
FORCEPROP 1 LAST MATERIAL X6S
J 0
(-6900 2700);
DISPLAY 0.617021 (-6900 2700);
PAINT SKYBLUE (-6900 2700);
FORCEPROP 1 LAST LOCATION C5G81
J 0
(-6900 2900);
DISPLAY 0.617021 (-6900 2900);
PAINT AQUA (-6900 2900);
FORCEPROP 1 LAST VALUE 22.0UF
J 0
(-6900 2850);
DISPLAY 0.617021 (-6900 2850);
PAINT SKYBLUE (-6900 2850);
FORCEPROP 1 LAST TOLERANCE 20%
J 0
(-6900 2750);
DISPLAY 0.617021 (-6900 2750);
PAINT SKYBLUE (-6900 2750);
FORCEPROP 1 LAST VOLTAGE 4V
J 0
(-6900 2800);
DISPLAY 0.617021 (-6900 2800);
PAINT SKYBLUE (-6900 2800);
FORCEPROP 0 LAST GROUP PWR_MLCC_CAP
J 0
(-6894 2512);
DISPLAY 0.638298 (-6894 2512);
PAINT BROWN (-6894 2512);
DISPLAY BOTH (-6894 2512);
FORCEPROP 0 LAST BOM_DS NOPOP
J 0
(-6900 2550);
DISPLAY 0.638298 (-6900 2550);
PAINT BROWN (-6900 2550);
DISPLAY BOTH (-6900 2550);
FORCEPROP 2 LAST CDS_LIB dev_discrete
J 0
(-6950 2800);
PAINT MONO (-6950 2800);
DISPLAY INVISIBLE (-6950 2800);
FORCEPROP 1 LAST PATH I60
J 0
(-6900 2950);
DISPLAY 0.978723 (-6900 2950);
PAINT WHITE (-6900 2950);
DISPLAY INVISIBLE (-6900 2950);
FORCEPROP 0 LAST ROOM PVDDQ_KLM
J 0
(-6900 3000);
DISPLAY 1.021277 (-6900 3000);
PAINT ORANGE (-6900 3000);
DISPLAY INVISIBLE (-6900 3000);
FORCEPROP 0 LAST SEC 1
J 0
(-6900 2950);
DISPLAY 0.680851 (-6900 2950);
PAINT MONO (-6900 2950);
DISPLAY INVISIBLE (-6900 2950);
FORCEPROP 2 LAST SEC_TYPE 0603V
J 0
(-6900 3000);
DISPLAY 1.021277 (-6900 3000);
PAINT ORANGE (-6900 3000);
DISPLAY INVISIBLE (-6900 3000);
FORCEADD CAP_A..1
(-7350 2800);
FORCEPROP 1 LAST LOCATION C5G80
J 0
(-7300 2900);
DISPLAY 0.617021 (-7300 2900);
PAINT AQUA (-7300 2900);
FORCEPROP 1 LAST MATERIAL X6S
J 0
(-7300 2700);
DISPLAY 0.617021 (-7300 2700);
PAINT SKYBLUE (-7300 2700);
FORCEPROP 1 LAST VALUE 22.0UF
J 0
(-7300 2850);
DISPLAY 0.617021 (-7300 2850);
PAINT SKYBLUE (-7300 2850);
FORCEPROP 1 LAST PACK_TYPE 0603V
J 0
(-7300 2600);
DISPLAY 0.617021 (-7300 2600);
PAINT SKYBLUE (-7300 2600);
FORCEPROP 1 LASTPIN (-7350 2700) $PN 2
J 0
(-7340 2680);
DISPLAY 0.787234 (-7340 2680);
PAINT ORANGE (-7340 2680);
FORCEPROP 1 LASTPIN (-7350 2900) $PN 1
J 0
(-7340 2880);
DISPLAY 0.787234 (-7340 2880);
PAINT ORANGE (-7340 2880);
FORCEPROP 1 LAST VOLTAGE 4V
J 0
(-7300 2800);
DISPLAY 0.617021 (-7300 2800);
PAINT SKYBLUE (-7300 2800);
FORCEPROP 1 LAST TOLERANCE 20%
J 0
(-7300 2750);
DISPLAY 0.617021 (-7300 2750);
PAINT SKYBLUE (-7300 2750);
FORCEPROP 1 LAST PART_NUMBER E15431-004
J 0
(-7300 2650);
DISPLAY 0.617021 (-7300 2650);
PAINT BLUE (-7300 2650);
FORCEPROP 0 LAST GROUP PWR_MLCC_CAP
J 0
(-7294 2462);
DISPLAY 0.638298 (-7294 2462);
PAINT BROWN (-7294 2462);
DISPLAY BOTH (-7294 2462);
FORCEPROP 0 LAST BOM_DS NOPOP
J 0
(-7300 2550);
DISPLAY 0.638298 (-7300 2550);
PAINT BROWN (-7300 2550);
DISPLAY BOTH (-7300 2550);
FORCEPROP 2 LAST CDS_LIB dev_discrete
J 0
(-7350 2800);
PAINT MONO (-7350 2800);
DISPLAY INVISIBLE (-7350 2800);
FORCEPROP 1 LAST PATH I61
J 0
(-7300 2950);
DISPLAY 0.978723 (-7300 2950);
PAINT WHITE (-7300 2950);
DISPLAY INVISIBLE (-7300 2950);
FORCEPROP 0 LAST ROOM PVDDQ_KLM
J 0
(-7300 3000);
DISPLAY 1.021277 (-7300 3000);
PAINT ORANGE (-7300 3000);
DISPLAY INVISIBLE (-7300 3000);
FORCEPROP 0 LAST SEC 1
J 0
(-7300 2950);
DISPLAY 0.680851 (-7300 2950);
PAINT MONO (-7300 2950);
DISPLAY INVISIBLE (-7300 2950);
FORCEPROP 2 LAST SEC_TYPE 0603V
J 0
(-7300 3000);
DISPLAY 1.021277 (-7300 3000);
PAINT ORANGE (-7300 3000);
DISPLAY INVISIBLE (-7300 3000);
FORCEADD CAP_A..1
(-4550 1850);
FORCEPROP 0 LAST BOM_DS NOPOP
J 0
(-4500 1600);
DISPLAY 0.638298 (-4500 1600);
PAINT BROWN (-4500 1600);
DISPLAY BOTH (-4500 1600);
FORCEPROP 0 LAST GROUP PWR_MLCC_CAP
J 0
(-4494 1562);
DISPLAY 0.638298 (-4494 1562);
PAINT BROWN (-4494 1562);
DISPLAY BOTH (-4494 1562);
FORCEPROP 1 LAST PACK_TYPE 0603V
J 0
(-4500 1650);
DISPLAY 0.617021 (-4500 1650);
PAINT SKYBLUE (-4500 1650);
FORCEPROP 1 LAST PART_NUMBER E15431-004
J 0
(-4500 1700);
DISPLAY 0.617021 (-4500 1700);
PAINT BLUE (-4500 1700);
FORCEPROP 1 LASTPIN (-4550 1750) $PN 2
J 0
(-4540 1730);
DISPLAY 0.787234 (-4540 1730);
PAINT ORANGE (-4540 1730);
FORCEPROP 1 LAST MATERIAL X6S
J 0
(-4500 1750);
DISPLAY 0.617021 (-4500 1750);
PAINT SKYBLUE (-4500 1750);
FORCEPROP 1 LAST VOLTAGE 4V
J 0
(-4500 1850);
DISPLAY 0.617021 (-4500 1850);
PAINT SKYBLUE (-4500 1850);
FORCEPROP 1 LAST TOLERANCE 20%
J 0
(-4500 1800);
DISPLAY 0.617021 (-4500 1800);
PAINT SKYBLUE (-4500 1800);
FORCEPROP 1 LAST VALUE 22.0UF
J 0
(-4500 1900);
DISPLAY 0.617021 (-4500 1900);
PAINT SKYBLUE (-4500 1900);
FORCEPROP 1 LAST LOCATION C5G96
J 0
(-4500 1950);
DISPLAY 0.617021 (-4500 1950);
PAINT AQUA (-4500 1950);
FORCEPROP 1 LASTPIN (-4550 1950) $PN 1
J 0
(-4540 1930);
DISPLAY 0.787234 (-4540 1930);
PAINT ORANGE (-4540 1930);
FORCEPROP 2 LAST SEC_TYPE 0603V
J 0
(-4500 2050);
DISPLAY 1.021277 (-4500 2050);
PAINT ORANGE (-4500 2050);
DISPLAY INVISIBLE (-4500 2050);
FORCEPROP 0 LAST SEC 1
J 0
(-4500 2000);
DISPLAY 0.680851 (-4500 2000);
PAINT MONO (-4500 2000);
DISPLAY INVISIBLE (-4500 2000);
FORCEPROP 2 LAST CDS_LIB dev_discrete
J 0
(-4550 1850);
PAINT MONO (-4550 1850);
DISPLAY INVISIBLE (-4550 1850);
FORCEPROP 1 LAST PATH I62
J 0
(-4500 2000);
DISPLAY 0.978723 (-4500 2000);
PAINT WHITE (-4500 2000);
DISPLAY INVISIBLE (-4500 2000);
FORCEPROP 0 LAST ROOM PVDDQ_KLM
J 0
(-4500 2050);
DISPLAY 1.021277 (-4500 2050);
PAINT ORANGE (-4500 2050);
DISPLAY INVISIBLE (-4500 2050);
FORCEADD CAP_A..1
(-4950 1850);
FORCEPROP 0 LAST BOM_DS NOPOP
J 0
(-4900 1600);
DISPLAY 0.638298 (-4900 1600);
PAINT BROWN (-4900 1600);
DISPLAY BOTH (-4900 1600);
FORCEPROP 0 LAST GROUP PWR_MLCC_CAP
J 0
(-4894 1512);
DISPLAY 0.638298 (-4894 1512);
PAINT BROWN (-4894 1512);
DISPLAY BOTH (-4894 1512);
FORCEPROP 1 LAST PART_NUMBER E15431-004
J 0
(-4900 1700);
DISPLAY 0.617021 (-4900 1700);
PAINT BLUE (-4900 1700);
FORCEPROP 1 LAST TOLERANCE 20%
J 0
(-4900 1800);
DISPLAY 0.617021 (-4900 1800);
PAINT SKYBLUE (-4900 1800);
FORCEPROP 1 LAST MATERIAL X6S
J 0
(-4900 1750);
DISPLAY 0.617021 (-4900 1750);
PAINT SKYBLUE (-4900 1750);
FORCEPROP 1 LAST VOLTAGE 4V
J 0
(-4900 1850);
DISPLAY 0.617021 (-4900 1850);
PAINT SKYBLUE (-4900 1850);
FORCEPROP 1 LAST LOCATION C5G95
J 0
(-4900 1950);
DISPLAY 0.617021 (-4900 1950);
PAINT AQUA (-4900 1950);
FORCEPROP 1 LAST PACK_TYPE 0603V
J 0
(-4900 1650);
DISPLAY 0.617021 (-4900 1650);
PAINT SKYBLUE (-4900 1650);
FORCEPROP 1 LASTPIN (-4950 1750) $PN 2
J 0
(-4940 1730);
DISPLAY 0.787234 (-4940 1730);
PAINT ORANGE (-4940 1730);
FORCEPROP 1 LASTPIN (-4950 1950) $PN 1
J 0
(-4940 1930);
DISPLAY 0.787234 (-4940 1930);
PAINT ORANGE (-4940 1930);
FORCEPROP 1 LAST VALUE 22.0UF
J 0
(-4900 1900);
DISPLAY 0.617021 (-4900 1900);
PAINT SKYBLUE (-4900 1900);
FORCEPROP 0 LAST ROOM PVDDQ_KLM
J 0
(-4900 2050);
DISPLAY 1.021277 (-4900 2050);
PAINT ORANGE (-4900 2050);
DISPLAY INVISIBLE (-4900 2050);
FORCEPROP 1 LAST PATH I63
J 0
(-4900 2000);
DISPLAY 0.978723 (-4900 2000);
PAINT WHITE (-4900 2000);
DISPLAY INVISIBLE (-4900 2000);
FORCEPROP 2 LAST CDS_LIB dev_discrete
J 0
(-4950 1850);
PAINT MONO (-4950 1850);
DISPLAY INVISIBLE (-4950 1850);
FORCEPROP 0 LAST SEC 1
J 0
(-4900 2000);
DISPLAY 0.680851 (-4900 2000);
PAINT MONO (-4900 2000);
DISPLAY INVISIBLE (-4900 2000);
FORCEPROP 2 LAST SEC_TYPE 0603V
J 0
(-4900 2050);
DISPLAY 1.021277 (-4900 2050);
PAINT ORANGE (-4900 2050);
DISPLAY INVISIBLE (-4900 2050);
FORCEADD CAP_A..1
(-5350 1850);
FORCEPROP 1 LAST VALUE 22.0UF
J 0
(-5300 1900);
DISPLAY 0.617021 (-5300 1900);
PAINT SKYBLUE (-5300 1900);
FORCEPROP 1 LASTPIN (-5350 1950) $PN 1
J 0
(-5340 1930);
DISPLAY 0.787234 (-5340 1930);
PAINT ORANGE (-5340 1930);
FORCEPROP 1 LASTPIN (-5350 1750) $PN 2
J 0
(-5340 1730);
DISPLAY 0.787234 (-5340 1730);
PAINT ORANGE (-5340 1730);
FORCEPROP 1 LAST LOCATION C5G94
J 0
(-5300 1950);
DISPLAY 0.617021 (-5300 1950);
PAINT AQUA (-5300 1950);
FORCEPROP 1 LAST TOLERANCE 20%
J 0
(-5300 1800);
DISPLAY 0.617021 (-5300 1800);
PAINT SKYBLUE (-5300 1800);
FORCEPROP 1 LAST VOLTAGE 4V
J 0
(-5300 1850);
DISPLAY 0.617021 (-5300 1850);
PAINT SKYBLUE (-5300 1850);
FORCEPROP 1 LAST PACK_TYPE 0603V
J 0
(-5300 1650);
DISPLAY 0.617021 (-5300 1650);
PAINT SKYBLUE (-5300 1650);
FORCEPROP 1 LAST PART_NUMBER E15431-004
J 0
(-5300 1700);
DISPLAY 0.617021 (-5300 1700);
PAINT BLUE (-5300 1700);
FORCEPROP 1 LAST MATERIAL X6S
J 0
(-5300 1750);
DISPLAY 0.617021 (-5300 1750);
PAINT SKYBLUE (-5300 1750);
FORCEPROP 0 LAST GROUP PWR_MLCC_CAP
J 0
(-5294 1562);
DISPLAY 0.638298 (-5294 1562);
PAINT BROWN (-5294 1562);
DISPLAY BOTH (-5294 1562);
FORCEPROP 0 LAST BOM_DS NOPOP
J 0
(-5300 1600);
DISPLAY 0.638298 (-5300 1600);
PAINT BROWN (-5300 1600);
DISPLAY BOTH (-5300 1600);
FORCEPROP 2 LAST SEC_TYPE 0603V
J 0
(-5300 2050);
DISPLAY 1.021277 (-5300 2050);
PAINT ORANGE (-5300 2050);
DISPLAY INVISIBLE (-5300 2050);
FORCEPROP 0 LAST SEC 1
J 0
(-5300 2000);
DISPLAY 0.680851 (-5300 2000);
PAINT MONO (-5300 2000);
DISPLAY INVISIBLE (-5300 2000);
FORCEPROP 2 LAST CDS_LIB dev_discrete
J 0
(-5350 1850);
PAINT MONO (-5350 1850);
DISPLAY INVISIBLE (-5350 1850);
FORCEPROP 1 LAST PATH I64
J 0
(-5300 2000);
DISPLAY 0.978723 (-5300 2000);
PAINT WHITE (-5300 2000);
DISPLAY INVISIBLE (-5300 2000);
FORCEPROP 0 LAST ROOM PVDDQ_KLM
J 0
(-5300 2050);
DISPLAY 1.021277 (-5300 2050);
PAINT ORANGE (-5300 2050);
DISPLAY INVISIBLE (-5300 2050);
FORCEADD CAP_A..1
(-5750 1850);
FORCEPROP 1 LAST TOLERANCE 20%
J 0
(-5700 1800);
DISPLAY 0.617021 (-5700 1800);
PAINT SKYBLUE (-5700 1800);
FORCEPROP 1 LASTPIN (-5750 1950) $PN 1
J 0
(-5740 1930);
DISPLAY 0.787234 (-5740 1930);
PAINT ORANGE (-5740 1930);
FORCEPROP 1 LAST PACK_TYPE 0603V
J 0
(-5700 1650);
DISPLAY 0.617021 (-5700 1650);
PAINT SKYBLUE (-5700 1650);
FORCEPROP 1 LAST LOCATION C5G93
J 0
(-5700 1950);
DISPLAY 0.617021 (-5700 1950);
PAINT AQUA (-5700 1950);
FORCEPROP 1 LAST VALUE 22.0UF
J 0
(-5700 1900);
DISPLAY 0.617021 (-5700 1900);
PAINT SKYBLUE (-5700 1900);
FORCEPROP 1 LAST VOLTAGE 4V
J 0
(-5700 1850);
DISPLAY 0.617021 (-5700 1850);
PAINT SKYBLUE (-5700 1850);
FORCEPROP 1 LAST PART_NUMBER E15431-004
J 0
(-5700 1700);
DISPLAY 0.617021 (-5700 1700);
PAINT BLUE (-5700 1700);
FORCEPROP 1 LAST MATERIAL X6S
J 0
(-5700 1750);
DISPLAY 0.617021 (-5700 1750);
PAINT SKYBLUE (-5700 1750);
FORCEPROP 1 LASTPIN (-5750 1750) $PN 2
J 0
(-5740 1730);
DISPLAY 0.787234 (-5740 1730);
PAINT ORANGE (-5740 1730);
FORCEPROP 0 LAST GROUP PWR_MLCC_CAP
J 0
(-5694 1512);
DISPLAY 0.638298 (-5694 1512);
PAINT BROWN (-5694 1512);
DISPLAY BOTH (-5694 1512);
FORCEPROP 0 LAST BOM_DS NOPOP
J 0
(-5700 1600);
DISPLAY 0.638298 (-5700 1600);
PAINT BROWN (-5700 1600);
DISPLAY BOTH (-5700 1600);
FORCEPROP 2 LAST SEC_TYPE 0603V
J 0
(-5700 2050);
DISPLAY 1.021277 (-5700 2050);
PAINT ORANGE (-5700 2050);
DISPLAY INVISIBLE (-5700 2050);
FORCEPROP 0 LAST SEC 1
J 0
(-5700 2000);
DISPLAY 0.680851 (-5700 2000);
PAINT MONO (-5700 2000);
DISPLAY INVISIBLE (-5700 2000);
FORCEPROP 2 LAST CDS_LIB dev_discrete
J 0
(-5750 1850);
PAINT MONO (-5750 1850);
DISPLAY INVISIBLE (-5750 1850);
FORCEPROP 1 LAST PATH I65
J 0
(-5700 2000);
DISPLAY 0.978723 (-5700 2000);
PAINT WHITE (-5700 2000);
DISPLAY INVISIBLE (-5700 2000);
FORCEPROP 0 LAST ROOM PVDDQ_KLM
J 0
(-5700 2050);
DISPLAY 1.021277 (-5700 2050);
PAINT ORANGE (-5700 2050);
DISPLAY INVISIBLE (-5700 2050);
FORCEADD CAP_A..1
(-6150 1850);
FORCEPROP 1 LAST PACK_TYPE 0603V
J 0
(-6100 1650);
DISPLAY 0.617021 (-6100 1650);
PAINT SKYBLUE (-6100 1650);
FORCEPROP 1 LASTPIN (-6150 1950) $PN 1
J 0
(-6140 1930);
DISPLAY 0.787234 (-6140 1930);
PAINT ORANGE (-6140 1930);
FORCEPROP 1 LASTPIN (-6150 1750) $PN 2
J 0
(-6140 1730);
DISPLAY 0.787234 (-6140 1730);
PAINT ORANGE (-6140 1730);
FORCEPROP 1 LAST LOCATION C5G92
J 0
(-6100 1950);
DISPLAY 0.617021 (-6100 1950);
PAINT AQUA (-6100 1950);
FORCEPROP 1 LAST VALUE 22.0UF
J 0
(-6100 1900);
DISPLAY 0.617021 (-6100 1900);
PAINT SKYBLUE (-6100 1900);
FORCEPROP 1 LAST VOLTAGE 4V
J 0
(-6100 1850);
DISPLAY 0.617021 (-6100 1850);
PAINT SKYBLUE (-6100 1850);
FORCEPROP 1 LAST TOLERANCE 20%
J 0
(-6100 1800);
DISPLAY 0.617021 (-6100 1800);
PAINT SKYBLUE (-6100 1800);
FORCEPROP 1 LAST PART_NUMBER E15431-004
J 0
(-6100 1700);
DISPLAY 0.617021 (-6100 1700);
PAINT BLUE (-6100 1700);
FORCEPROP 1 LAST MATERIAL X6S
J 0
(-6100 1750);
DISPLAY 0.617021 (-6100 1750);
PAINT SKYBLUE (-6100 1750);
FORCEPROP 0 LAST GROUP PWR_MLCC_CAP
J 0
(-6094 1562);
DISPLAY 0.638298 (-6094 1562);
PAINT BROWN (-6094 1562);
DISPLAY BOTH (-6094 1562);
FORCEPROP 0 LAST BOM_DS NOPOP
J 0
(-6100 1600);
DISPLAY 0.638298 (-6100 1600);
PAINT BROWN (-6100 1600);
DISPLAY BOTH (-6100 1600);
FORCEPROP 2 LAST SEC_TYPE 0603V
J 0
(-6100 2050);
DISPLAY 1.021277 (-6100 2050);
PAINT ORANGE (-6100 2050);
DISPLAY INVISIBLE (-6100 2050);
FORCEPROP 0 LAST SEC 1
J 0
(-6100 2000);
DISPLAY 0.680851 (-6100 2000);
PAINT MONO (-6100 2000);
DISPLAY INVISIBLE (-6100 2000);
FORCEPROP 2 LAST CDS_LIB dev_discrete
J 0
(-6150 1850);
PAINT MONO (-6150 1850);
DISPLAY INVISIBLE (-6150 1850);
FORCEPROP 1 LAST PATH I66
J 0
(-6100 2000);
DISPLAY 0.978723 (-6100 2000);
PAINT WHITE (-6100 2000);
DISPLAY INVISIBLE (-6100 2000);
FORCEPROP 0 LAST ROOM PVDDQ_KLM
J 0
(-6100 2050);
DISPLAY 1.021277 (-6100 2050);
PAINT ORANGE (-6100 2050);
DISPLAY INVISIBLE (-6100 2050);
FORCEADD CAP_A..1
(-6550 1850);
FORCEPROP 1 LASTPIN (-6550 1950) $PN 1
J 0
(-6540 1930);
DISPLAY 0.787234 (-6540 1930);
PAINT ORANGE (-6540 1930);
FORCEPROP 1 LAST PACK_TYPE 0603V
J 0
(-6500 1650);
DISPLAY 0.617021 (-6500 1650);
PAINT SKYBLUE (-6500 1650);
FORCEPROP 1 LAST MATERIAL X6S
J 0
(-6500 1750);
DISPLAY 0.617021 (-6500 1750);
PAINT SKYBLUE (-6500 1750);
FORCEPROP 1 LAST LOCATION C5G91
J 0
(-6500 1950);
DISPLAY 0.617021 (-6500 1950);
PAINT AQUA (-6500 1950);
FORCEPROP 1 LAST VALUE 22.0UF
J 0
(-6500 1900);
DISPLAY 0.617021 (-6500 1900);
PAINT SKYBLUE (-6500 1900);
FORCEPROP 1 LAST VOLTAGE 4V
J 0
(-6500 1850);
DISPLAY 0.617021 (-6500 1850);
PAINT SKYBLUE (-6500 1850);
FORCEPROP 1 LAST TOLERANCE 20%
J 0
(-6500 1800);
DISPLAY 0.617021 (-6500 1800);
PAINT SKYBLUE (-6500 1800);
FORCEPROP 1 LAST PART_NUMBER E15431-004
J 0
(-6500 1700);
DISPLAY 0.617021 (-6500 1700);
PAINT BLUE (-6500 1700);
FORCEPROP 1 LASTPIN (-6550 1750) $PN 2
J 0
(-6540 1730);
DISPLAY 0.787234 (-6540 1730);
PAINT ORANGE (-6540 1730);
FORCEPROP 0 LAST GROUP PWR_MLCC_CAP
J 0
(-6494 1487);
DISPLAY 0.638298 (-6494 1487);
PAINT BROWN (-6494 1487);
DISPLAY BOTH (-6494 1487);
FORCEPROP 0 LAST BOM_DS NOPOP
J 0
(-6500 1600);
DISPLAY 0.638298 (-6500 1600);
PAINT BROWN (-6500 1600);
DISPLAY BOTH (-6500 1600);
FORCEPROP 2 LAST SEC_TYPE 0603V
J 0
(-6500 2050);
DISPLAY 1.021277 (-6500 2050);
PAINT ORANGE (-6500 2050);
DISPLAY INVISIBLE (-6500 2050);
FORCEPROP 0 LAST SEC 1
J 0
(-6500 2000);
DISPLAY 0.680851 (-6500 2000);
PAINT MONO (-6500 2000);
DISPLAY INVISIBLE (-6500 2000);
FORCEPROP 0 LAST ROOM PVDDQ_KLM
J 0
(-6500 2050);
DISPLAY 1.021277 (-6500 2050);
PAINT ORANGE (-6500 2050);
DISPLAY INVISIBLE (-6500 2050);
FORCEPROP 1 LAST PATH I67
J 0
(-6500 2000);
DISPLAY 0.978723 (-6500 2000);
PAINT WHITE (-6500 2000);
DISPLAY INVISIBLE (-6500 2000);
FORCEPROP 2 LAST CDS_LIB dev_discrete
J 0
(-6550 1850);
PAINT MONO (-6550 1850);
DISPLAY INVISIBLE (-6550 1850);
FORCEADD CAP_A..1
(-6950 1850);
FORCEPROP 1 LAST VOLTAGE 4V
J 0
(-6900 1850);
DISPLAY 0.617021 (-6900 1850);
PAINT SKYBLUE (-6900 1850);
FORCEPROP 1 LAST LOCATION C5G90
J 0
(-6900 1950);
DISPLAY 0.617021 (-6900 1950);
PAINT AQUA (-6900 1950);
FORCEPROP 1 LAST VALUE 22.0UF
J 0
(-6900 1900);
DISPLAY 0.617021 (-6900 1900);
PAINT SKYBLUE (-6900 1900);
FORCEPROP 1 LAST MATERIAL X6S
J 0
(-6900 1750);
DISPLAY 0.617021 (-6900 1750);
PAINT SKYBLUE (-6900 1750);
FORCEPROP 1 LAST PACK_TYPE 0603V
J 0
(-6900 1650);
DISPLAY 0.617021 (-6900 1650);
PAINT SKYBLUE (-6900 1650);
FORCEPROP 1 LASTPIN (-6950 1750) $PN 2
J 0
(-6940 1730);
DISPLAY 0.787234 (-6940 1730);
PAINT ORANGE (-6940 1730);
FORCEPROP 1 LASTPIN (-6950 1950) $PN 1
J 0
(-6940 1930);
DISPLAY 0.787234 (-6940 1930);
PAINT ORANGE (-6940 1930);
FORCEPROP 1 LAST TOLERANCE 20%
J 0
(-6900 1800);
DISPLAY 0.617021 (-6900 1800);
PAINT SKYBLUE (-6900 1800);
FORCEPROP 1 LAST PART_NUMBER E15431-004
J 0
(-6900 1700);
DISPLAY 0.617021 (-6900 1700);
PAINT BLUE (-6900 1700);
FORCEPROP 0 LAST GROUP PWR_MLCC_CAP
J 0
(-6894 1562);
DISPLAY 0.638298 (-6894 1562);
PAINT BROWN (-6894 1562);
DISPLAY BOTH (-6894 1562);
FORCEPROP 0 LAST BOM_DS NOPOP
J 0
(-6900 1600);
DISPLAY 0.638298 (-6900 1600);
PAINT BROWN (-6900 1600);
DISPLAY BOTH (-6900 1600);
FORCEPROP 0 LAST ROOM PVDDQ_KLM
J 0
(-6900 2050);
DISPLAY 1.021277 (-6900 2050);
PAINT ORANGE (-6900 2050);
DISPLAY INVISIBLE (-6900 2050);
FORCEPROP 1 LAST PATH I68
J 0
(-6900 2000);
DISPLAY 0.978723 (-6900 2000);
PAINT WHITE (-6900 2000);
DISPLAY INVISIBLE (-6900 2000);
FORCEPROP 2 LAST CDS_LIB dev_discrete
J 0
(-6950 1850);
PAINT MONO (-6950 1850);
DISPLAY INVISIBLE (-6950 1850);
FORCEPROP 0 LAST SEC 1
J 0
(-6900 2000);
DISPLAY 0.680851 (-6900 2000);
PAINT MONO (-6900 2000);
DISPLAY INVISIBLE (-6900 2000);
FORCEPROP 2 LAST SEC_TYPE 0603V
J 0
(-6900 2050);
DISPLAY 1.021277 (-6900 2050);
PAINT ORANGE (-6900 2050);
DISPLAY INVISIBLE (-6900 2050);
FORCEADD CAP_A..1
(-7350 1850);
FORCEPROP 1 LAST VOLTAGE 4V
J 0
(-7300 1850);
DISPLAY 0.617021 (-7300 1850);
PAINT SKYBLUE (-7300 1850);
FORCEPROP 1 LAST VALUE 22.0UF
J 0
(-7300 1900);
DISPLAY 0.617021 (-7300 1900);
PAINT SKYBLUE (-7300 1900);
FORCEPROP 1 LASTPIN (-7350 1950) $PN 1
J 0
(-7340 1930);
DISPLAY 0.787234 (-7340 1930);
PAINT ORANGE (-7340 1930);
FORCEPROP 1 LASTPIN (-7350 1750) $PN 2
J 0
(-7340 1730);
DISPLAY 0.787234 (-7340 1730);
PAINT ORANGE (-7340 1730);
FORCEPROP 1 LAST MATERIAL X6S
J 0
(-7300 1750);
DISPLAY 0.617021 (-7300 1750);
PAINT SKYBLUE (-7300 1750);
FORCEPROP 1 LAST LOCATION C5G89
J 0
(-7300 1950);
DISPLAY 0.617021 (-7300 1950);
PAINT AQUA (-7300 1950);
FORCEPROP 1 LAST TOLERANCE 20%
J 0
(-7300 1800);
DISPLAY 0.617021 (-7300 1800);
PAINT SKYBLUE (-7300 1800);
FORCEPROP 1 LAST PACK_TYPE 0603V
J 0
(-7300 1650);
DISPLAY 0.617021 (-7300 1650);
PAINT SKYBLUE (-7300 1650);
FORCEPROP 1 LAST PART_NUMBER E15431-004
J 0
(-7300 1700);
DISPLAY 0.617021 (-7300 1700);
PAINT BLUE (-7300 1700);
FORCEPROP 0 LAST GROUP PWR_MLCC_CAP
J 0
(-7294 1512);
DISPLAY 0.638298 (-7294 1512);
PAINT BROWN (-7294 1512);
DISPLAY BOTH (-7294 1512);
FORCEPROP 0 LAST BOM_DS NOPOP
J 0
(-7300 1600);
DISPLAY 0.638298 (-7300 1600);
PAINT BROWN (-7300 1600);
DISPLAY BOTH (-7300 1600);
FORCEPROP 2 LAST SEC_TYPE 0603V
J 0
(-7300 2050);
DISPLAY 1.021277 (-7300 2050);
PAINT ORANGE (-7300 2050);
DISPLAY INVISIBLE (-7300 2050);
FORCEPROP 0 LAST SEC 1
J 0
(-7300 2000);
DISPLAY 0.680851 (-7300 2000);
PAINT MONO (-7300 2000);
DISPLAY INVISIBLE (-7300 2000);
FORCEPROP 0 LAST ROOM PVDDQ_KLM
J 0
(-7300 2050);
DISPLAY 1.021277 (-7300 2050);
PAINT ORANGE (-7300 2050);
DISPLAY INVISIBLE (-7300 2050);
FORCEPROP 1 LAST PATH I69
J 0
(-7300 2000);
DISPLAY 0.978723 (-7300 2000);
PAINT WHITE (-7300 2000);
DISPLAY INVISIBLE (-7300 2000);
FORCEPROP 2 LAST CDS_LIB dev_discrete
J 0
(-7350 1850);
PAINT MONO (-7350 1850);
DISPLAY INVISIBLE (-7350 1850);
FORCEADD CAP_A..1
(-7750 1850);
FORCEPROP 1 LAST TOLERANCE 20%
J 0
(-7700 1800);
DISPLAY 0.617021 (-7700 1800);
PAINT SKYBLUE (-7700 1800);
FORCEPROP 1 LAST MATERIAL X6S
J 0
(-7700 1750);
DISPLAY 0.617021 (-7700 1750);
PAINT SKYBLUE (-7700 1750);
FORCEPROP 1 LAST PACK_TYPE 0603V
J 0
(-7700 1650);
DISPLAY 0.617021 (-7700 1650);
PAINT SKYBLUE (-7700 1650);
FORCEPROP 1 LASTPIN (-7750 1950) $PN 1
J 0
(-7740 1930);
DISPLAY 0.787234 (-7740 1930);
PAINT ORANGE (-7740 1930);
FORCEPROP 1 LASTPIN (-7750 1750) $PN 2
J 0
(-7740 1730);
DISPLAY 0.787234 (-7740 1730);
PAINT ORANGE (-7740 1730);
FORCEPROP 1 LAST VOLTAGE 4V
J 0
(-7700 1850);
DISPLAY 0.617021 (-7700 1850);
PAINT SKYBLUE (-7700 1850);
FORCEPROP 1 LAST PART_NUMBER E15431-004
J 0
(-7700 1700);
DISPLAY 0.617021 (-7700 1700);
PAINT BLUE (-7700 1700);
FORCEPROP 1 LAST LOCATION C5G88
J 0
(-7700 1950);
DISPLAY 0.617021 (-7700 1950);
PAINT AQUA (-7700 1950);
FORCEPROP 1 LAST VALUE 22.0UF
J 0
(-7700 1900);
DISPLAY 0.617021 (-7700 1900);
PAINT SKYBLUE (-7700 1900);
FORCEPROP 0 LAST GROUP PWR_MLCC_CAP
J 0
(-7694 1562);
DISPLAY 0.638298 (-7694 1562);
PAINT BROWN (-7694 1562);
DISPLAY BOTH (-7694 1562);
FORCEPROP 0 LAST BOM_DS NOPOP
J 0
(-7700 1600);
DISPLAY 0.638298 (-7700 1600);
PAINT BROWN (-7700 1600);
DISPLAY BOTH (-7700 1600);
FORCEPROP 2 LAST SEC_TYPE 0603V
J 0
(-7700 2050);
DISPLAY 1.021277 (-7700 2050);
PAINT ORANGE (-7700 2050);
DISPLAY INVISIBLE (-7700 2050);
FORCEPROP 0 LAST SEC 1
J 0
(-7700 2000);
DISPLAY 0.680851 (-7700 2000);
PAINT MONO (-7700 2000);
DISPLAY INVISIBLE (-7700 2000);
FORCEPROP 0 LAST ROOM PVDDQ_KLM
J 0
(-7700 2050);
DISPLAY 1.021277 (-7700 2050);
PAINT ORANGE (-7700 2050);
DISPLAY INVISIBLE (-7700 2050);
FORCEPROP 1 LAST PATH I70
J 0
(-7700 2000);
DISPLAY 0.978723 (-7700 2000);
PAINT WHITE (-7700 2000);
DISPLAY INVISIBLE (-7700 2000);
FORCEPROP 2 LAST CDS_LIB dev_discrete
J 0
(-7750 1850);
PAINT MONO (-7750 1850);
DISPLAY INVISIBLE (-7750 1850);
FORCEADD CAP_A..1
(-1400 2800);
FORCEPROP 0 LAST BOM_DS NOPOP
J 0
(-1350 2550);
DISPLAY 0.638298 (-1350 2550);
PAINT BROWN (-1350 2550);
DISPLAY BOTH (-1350 2550);
FORCEPROP 1 LAST PART_NUMBER E15431-004
J 0
(-1350 2650);
DISPLAY 0.617021 (-1350 2650);
PAINT BLUE (-1350 2650);
FORCEPROP 1 LASTPIN (-1400 2900) $PN 1
J 0
(-1390 2880);
DISPLAY 0.787234 (-1390 2880);
PAINT ORANGE (-1390 2880);
FORCEPROP 1 LASTPIN (-1400 2700) $PN 2
J 0
(-1390 2680);
DISPLAY 0.787234 (-1390 2680);
PAINT ORANGE (-1390 2680);
FORCEPROP 1 LAST PACK_TYPE 0603V
J 0
(-1350 2600);
DISPLAY 0.617021 (-1350 2600);
PAINT SKYBLUE (-1350 2600);
FORCEPROP 1 LAST VOLTAGE 4V
J 0
(-1350 2800);
DISPLAY 0.617021 (-1350 2800);
PAINT SKYBLUE (-1350 2800);
FORCEPROP 1 LAST VALUE 22.0UF
J 0
(-1350 2850);
DISPLAY 0.617021 (-1350 2850);
PAINT SKYBLUE (-1350 2850);
FORCEPROP 1 LAST LOCATION C5G103
J 0
(-1350 2900);
DISPLAY 0.617021 (-1350 2900);
PAINT AQUA (-1350 2900);
FORCEPROP 1 LAST MATERIAL X6S
J 0
(-1350 2700);
DISPLAY 0.617021 (-1350 2700);
PAINT SKYBLUE (-1350 2700);
FORCEPROP 1 LAST TOLERANCE 20%
J 0
(-1350 2750);
DISPLAY 0.617021 (-1350 2750);
PAINT SKYBLUE (-1350 2750);
FORCEPROP 0 LAST GROUP PWR_MLCC_CAP
J 0
(-1344 2512);
DISPLAY 0.638298 (-1344 2512);
PAINT BROWN (-1344 2512);
DISPLAY BOTH (-1344 2512);
FORCEPROP 2 LAST SEC_TYPE 0603V
J 0
(-1350 3000);
DISPLAY 1.021277 (-1350 3000);
PAINT ORANGE (-1350 3000);
DISPLAY INVISIBLE (-1350 3000);
FORCEPROP 0 LAST SEC 1
J 0
(-1350 2950);
DISPLAY 0.680851 (-1350 2950);
PAINT MONO (-1350 2950);
DISPLAY INVISIBLE (-1350 2950);
FORCEPROP 0 LAST ROOM PVDDQ_KLM
J 0
(-1350 3000);
DISPLAY 1.021277 (-1350 3000);
PAINT ORANGE (-1350 3000);
DISPLAY INVISIBLE (-1350 3000);
FORCEPROP 1 LAST PATH I71
J 0
(-1350 2950);
DISPLAY 0.978723 (-1350 2950);
PAINT WHITE (-1350 2950);
DISPLAY INVISIBLE (-1350 2950);
FORCEPROP 2 LAST CDS_LIB dev_discrete
J 0
(-1400 2800);
PAINT MONO (-1400 2800);
DISPLAY INVISIBLE (-1400 2800);
FORCEADD CAP_A..1
(-1000 2800);
FORCEPROP 1 LAST PART_NUMBER E15431-004
J 0
(-950 2650);
DISPLAY 0.617021 (-950 2650);
PAINT BLUE (-950 2650);
FORCEPROP 1 LAST LOCATION C5G104
J 0
(-950 2900);
DISPLAY 0.617021 (-950 2900);
PAINT AQUA (-950 2900);
FORCEPROP 1 LAST VALUE 22.0UF
J 0
(-950 2850);
DISPLAY 0.617021 (-950 2850);
PAINT SKYBLUE (-950 2850);
FORCEPROP 1 LAST VOLTAGE 4V
J 0
(-950 2800);
DISPLAY 0.617021 (-950 2800);
PAINT SKYBLUE (-950 2800);
FORCEPROP 1 LAST MATERIAL X6S
J 0
(-950 2700);
DISPLAY 0.617021 (-950 2700);
PAINT SKYBLUE (-950 2700);
FORCEPROP 1 LAST PACK_TYPE 0603V
J 0
(-950 2600);
DISPLAY 0.617021 (-950 2600);
PAINT SKYBLUE (-950 2600);
FORCEPROP 1 LASTPIN (-1000 2700) $PN 2
J 0
(-990 2680);
DISPLAY 0.787234 (-990 2680);
PAINT ORANGE (-990 2680);
FORCEPROP 1 LASTPIN (-1000 2900) $PN 1
J 0
(-990 2880);
DISPLAY 0.787234 (-990 2880);
PAINT ORANGE (-990 2880);
FORCEPROP 1 LAST TOLERANCE 20%
J 0
(-950 2750);
DISPLAY 0.617021 (-950 2750);
PAINT SKYBLUE (-950 2750);
FORCEPROP 0 LAST GROUP PWR_MLCC_CAP
J 0
(-944 2462);
DISPLAY 0.638298 (-944 2462);
PAINT BROWN (-944 2462);
DISPLAY BOTH (-944 2462);
FORCEPROP 0 LAST BOM_DS NOPOP
J 0
(-950 2550);
DISPLAY 0.638298 (-950 2550);
PAINT BROWN (-950 2550);
DISPLAY BOTH (-950 2550);
FORCEPROP 2 LAST CDS_LIB dev_discrete
J 0
(-1000 2800);
PAINT MONO (-1000 2800);
DISPLAY INVISIBLE (-1000 2800);
FORCEPROP 1 LAST PATH I72
J 0
(-950 2950);
DISPLAY 0.978723 (-950 2950);
PAINT WHITE (-950 2950);
DISPLAY INVISIBLE (-950 2950);
FORCEPROP 0 LAST ROOM PVDDQ_KLM
J 0
(-950 3000);
DISPLAY 1.021277 (-950 3000);
PAINT ORANGE (-950 3000);
DISPLAY INVISIBLE (-950 3000);
FORCEPROP 0 LAST SEC 1
J 0
(-950 2950);
DISPLAY 0.680851 (-950 2950);
PAINT MONO (-950 2950);
DISPLAY INVISIBLE (-950 2950);
FORCEPROP 2 LAST SEC_TYPE 0603V
J 0
(-950 3000);
DISPLAY 1.021277 (-950 3000);
PAINT ORANGE (-950 3000);
DISPLAY INVISIBLE (-950 3000);
FORCEADD CAP_A..1
(-600 2800);
FORCEPROP 1 LAST PART_NUMBER E15431-004
J 0
(-550 2650);
DISPLAY 0.617021 (-550 2650);
PAINT BLUE (-550 2650);
FORCEPROP 1 LAST VALUE 22.0UF
J 0
(-550 2850);
DISPLAY 0.617021 (-550 2850);
PAINT SKYBLUE (-550 2850);
FORCEPROP 1 LAST TOLERANCE 20%
J 0
(-550 2750);
DISPLAY 0.617021 (-550 2750);
PAINT SKYBLUE (-550 2750);
FORCEPROP 1 LAST LOCATION C5G105
J 0
(-550 2900);
DISPLAY 0.617021 (-550 2900);
PAINT AQUA (-550 2900);
FORCEPROP 1 LAST MATERIAL X6S
J 0
(-550 2700);
DISPLAY 0.617021 (-550 2700);
PAINT SKYBLUE (-550 2700);
FORCEPROP 1 LAST VOLTAGE 4V
J 0
(-550 2800);
DISPLAY 0.617021 (-550 2800);
PAINT SKYBLUE (-550 2800);
FORCEPROP 1 LAST PACK_TYPE 0603V
J 0
(-550 2600);
DISPLAY 0.617021 (-550 2600);
PAINT SKYBLUE (-550 2600);
FORCEPROP 1 LASTPIN (-600 2700) $PN 2
J 0
(-590 2680);
DISPLAY 0.787234 (-590 2680);
PAINT ORANGE (-590 2680);
FORCEPROP 1 LASTPIN (-600 2900) $PN 1
J 0
(-590 2880);
DISPLAY 0.787234 (-590 2880);
PAINT ORANGE (-590 2880);
FORCEPROP 0 LAST GROUP PWR_MLCC_CAP
J 0
(-544 2512);
DISPLAY 0.638298 (-544 2512);
PAINT BROWN (-544 2512);
DISPLAY BOTH (-544 2512);
FORCEPROP 0 LAST BOM_DS NOPOP
J 0
(-550 2550);
DISPLAY 0.638298 (-550 2550);
PAINT BROWN (-550 2550);
DISPLAY BOTH (-550 2550);
FORCEPROP 2 LAST CDS_LIB dev_discrete
J 0
(-600 2800);
PAINT MONO (-600 2800);
DISPLAY INVISIBLE (-600 2800);
FORCEPROP 1 LAST PATH I73
J 0
(-550 2950);
DISPLAY 0.978723 (-550 2950);
PAINT WHITE (-550 2950);
DISPLAY INVISIBLE (-550 2950);
FORCEPROP 0 LAST ROOM PVDDQ_KLM
J 0
(-550 3000);
DISPLAY 1.021277 (-550 3000);
PAINT ORANGE (-550 3000);
DISPLAY INVISIBLE (-550 3000);
FORCEPROP 0 LAST SEC 1
J 0
(-550 2950);
DISPLAY 0.680851 (-550 2950);
PAINT MONO (-550 2950);
DISPLAY INVISIBLE (-550 2950);
FORCEPROP 2 LAST SEC_TYPE 0603V
J 0
(-550 3000);
DISPLAY 1.021277 (-550 3000);
PAINT ORANGE (-550 3000);
DISPLAY INVISIBLE (-550 3000);
FORCEADD CAP_A..1
(-1800 2800);
FORCEPROP 0 LAST GROUP PWR_MLCC_CAP
J 0
(-1744 2462);
DISPLAY 0.638298 (-1744 2462);
PAINT BROWN (-1744 2462);
DISPLAY BOTH (-1744 2462);
FORCEPROP 1 LAST VALUE 22.0UF
J 0
(-1750 2850);
DISPLAY 0.617021 (-1750 2850);
PAINT SKYBLUE (-1750 2850);
FORCEPROP 1 LAST MATERIAL X6S
J 0
(-1750 2700);
DISPLAY 0.617021 (-1750 2700);
PAINT SKYBLUE (-1750 2700);
FORCEPROP 1 LAST LOCATION C5G102
J 0
(-1750 2900);
DISPLAY 0.617021 (-1750 2900);
PAINT AQUA (-1750 2900);
FORCEPROP 1 LAST PACK_TYPE 0603V
J 0
(-1750 2600);
DISPLAY 0.617021 (-1750 2600);
PAINT SKYBLUE (-1750 2600);
FORCEPROP 1 LASTPIN (-1800 2700) $PN 2
J 0
(-1790 2680);
DISPLAY 0.787234 (-1790 2680);
PAINT ORANGE (-1790 2680);
FORCEPROP 1 LASTPIN (-1800 2900) $PN 1
J 0
(-1790 2880);
DISPLAY 0.787234 (-1790 2880);
PAINT ORANGE (-1790 2880);
FORCEPROP 1 LAST PART_NUMBER E15431-004
J 0
(-1750 2650);
DISPLAY 0.617021 (-1750 2650);
PAINT BLUE (-1750 2650);
FORCEPROP 1 LAST VOLTAGE 4V
J 0
(-1750 2800);
DISPLAY 0.617021 (-1750 2800);
PAINT SKYBLUE (-1750 2800);
FORCEPROP 1 LAST TOLERANCE 20%
J 0
(-1750 2750);
DISPLAY 0.617021 (-1750 2750);
PAINT SKYBLUE (-1750 2750);
FORCEPROP 0 LAST BOM_DS NOPOP
J 0
(-1750 2550);
DISPLAY 0.638298 (-1750 2550);
PAINT BROWN (-1750 2550);
DISPLAY BOTH (-1750 2550);
FORCEPROP 2 LAST CDS_LIB dev_discrete
J 0
(-1800 2800);
PAINT MONO (-1800 2800);
DISPLAY INVISIBLE (-1800 2800);
FORCEPROP 1 LAST PATH I74
J 0
(-1750 2950);
DISPLAY 0.978723 (-1750 2950);
PAINT WHITE (-1750 2950);
DISPLAY INVISIBLE (-1750 2950);
FORCEPROP 0 LAST ROOM PVDDQ_KLM
J 0
(-1750 3000);
DISPLAY 1.021277 (-1750 3000);
PAINT ORANGE (-1750 3000);
DISPLAY INVISIBLE (-1750 3000);
FORCEPROP 0 LAST SEC 1
J 0
(-1750 2950);
DISPLAY 0.680851 (-1750 2950);
PAINT MONO (-1750 2950);
DISPLAY INVISIBLE (-1750 2950);
FORCEPROP 2 LAST SEC_TYPE 0603V
J 0
(-1750 3000);
DISPLAY 1.021277 (-1750 3000);
PAINT ORANGE (-1750 3000);
DISPLAY INVISIBLE (-1750 3000);
FORCEADD CAP_A..1
(-2200 2800);
FORCEPROP 1 LASTPIN (-2200 2900) $PN 1
J 0
(-2190 2880);
DISPLAY 0.787234 (-2190 2880);
PAINT ORANGE (-2190 2880);
FORCEPROP 1 LASTPIN (-2200 2700) $PN 2
J 0
(-2190 2680);
DISPLAY 0.787234 (-2190 2680);
PAINT ORANGE (-2190 2680);
FORCEPROP 1 LAST PACK_TYPE 0603V
J 0
(-2150 2600);
DISPLAY 0.617021 (-2150 2600);
PAINT SKYBLUE (-2150 2600);
FORCEPROP 1 LAST MATERIAL X6S
J 0
(-2150 2700);
DISPLAY 0.617021 (-2150 2700);
PAINT SKYBLUE (-2150 2700);
FORCEPROP 1 LAST LOCATION C5G101
J 0
(-2150 2900);
DISPLAY 0.617021 (-2150 2900);
PAINT AQUA (-2150 2900);
FORCEPROP 1 LAST PART_NUMBER E15431-004
J 0
(-2150 2650);
DISPLAY 0.617021 (-2150 2650);
PAINT BLUE (-2150 2650);
FORCEPROP 1 LAST TOLERANCE 20%
J 0
(-2150 2750);
DISPLAY 0.617021 (-2150 2750);
PAINT SKYBLUE (-2150 2750);
FORCEPROP 1 LAST VOLTAGE 4V
J 0
(-2150 2800);
DISPLAY 0.617021 (-2150 2800);
PAINT SKYBLUE (-2150 2800);
FORCEPROP 1 LAST VALUE 22.0UF
J 0
(-2150 2850);
DISPLAY 0.617021 (-2150 2850);
PAINT SKYBLUE (-2150 2850);
FORCEPROP 0 LAST GROUP PWR_MLCC_CAP
J 0
(-2144 2512);
DISPLAY 0.638298 (-2144 2512);
PAINT BROWN (-2144 2512);
DISPLAY BOTH (-2144 2512);
FORCEPROP 0 LAST BOM_DS NOPOP
J 0
(-2150 2550);
DISPLAY 0.638298 (-2150 2550);
PAINT BROWN (-2150 2550);
DISPLAY BOTH (-2150 2550);
FORCEPROP 2 LAST SEC_TYPE 0603V
J 0
(-2150 3000);
DISPLAY 1.021277 (-2150 3000);
PAINT ORANGE (-2150 3000);
DISPLAY INVISIBLE (-2150 3000);
FORCEPROP 0 LAST SEC 1
J 0
(-2150 2950);
DISPLAY 0.680851 (-2150 2950);
PAINT MONO (-2150 2950);
DISPLAY INVISIBLE (-2150 2950);
FORCEPROP 0 LAST ROOM PVDDQ_KLM
J 0
(-2150 3000);
DISPLAY 1.021277 (-2150 3000);
PAINT ORANGE (-2150 3000);
DISPLAY INVISIBLE (-2150 3000);
FORCEPROP 1 LAST PATH I75
J 0
(-2150 2950);
DISPLAY 0.978723 (-2150 2950);
PAINT WHITE (-2150 2950);
DISPLAY INVISIBLE (-2150 2950);
FORCEPROP 2 LAST CDS_LIB dev_discrete
J 0
(-2200 2800);
PAINT MONO (-2200 2800);
DISPLAY INVISIBLE (-2200 2800);
FORCEADD CAP_A..1
(-2600 2800);
FORCEPROP 1 LAST PART_NUMBER E15431-004
J 0
(-2550 2650);
DISPLAY 0.617021 (-2550 2650);
PAINT BLUE (-2550 2650);
FORCEPROP 1 LASTPIN (-2600 2900) $PN 1
J 0
(-2590 2880);
DISPLAY 0.787234 (-2590 2880);
PAINT ORANGE (-2590 2880);
FORCEPROP 1 LASTPIN (-2600 2700) $PN 2
J 0
(-2590 2680);
DISPLAY 0.787234 (-2590 2680);
PAINT ORANGE (-2590 2680);
FORCEPROP 1 LAST MATERIAL X6S
J 0
(-2550 2700);
DISPLAY 0.617021 (-2550 2700);
PAINT SKYBLUE (-2550 2700);
FORCEPROP 1 LAST LOCATION C5G100
J 0
(-2550 2900);
DISPLAY 0.617021 (-2550 2900);
PAINT AQUA (-2550 2900);
FORCEPROP 1 LAST VALUE 22.0UF
J 0
(-2550 2850);
DISPLAY 0.617021 (-2550 2850);
PAINT SKYBLUE (-2550 2850);
FORCEPROP 1 LAST TOLERANCE 20%
J 0
(-2550 2750);
DISPLAY 0.617021 (-2550 2750);
PAINT SKYBLUE (-2550 2750);
FORCEPROP 1 LAST VOLTAGE 4V
J 0
(-2550 2800);
DISPLAY 0.617021 (-2550 2800);
PAINT SKYBLUE (-2550 2800);
FORCEPROP 1 LAST PACK_TYPE 0603V
J 0
(-2550 2600);
DISPLAY 0.617021 (-2550 2600);
PAINT SKYBLUE (-2550 2600);
FORCEPROP 0 LAST GROUP PWR_MLCC_CAP
J 0
(-2544 2462);
DISPLAY 0.638298 (-2544 2462);
PAINT BROWN (-2544 2462);
DISPLAY BOTH (-2544 2462);
FORCEPROP 0 LAST BOM_DS NOPOP
J 0
(-2550 2550);
DISPLAY 0.638298 (-2550 2550);
PAINT BROWN (-2550 2550);
DISPLAY BOTH (-2550 2550);
FORCEPROP 2 LAST SEC_TYPE 0603V
J 0
(-2550 3000);
DISPLAY 1.021277 (-2550 3000);
PAINT ORANGE (-2550 3000);
DISPLAY INVISIBLE (-2550 3000);
FORCEPROP 0 LAST SEC 1
J 0
(-2550 2950);
DISPLAY 0.680851 (-2550 2950);
PAINT MONO (-2550 2950);
DISPLAY INVISIBLE (-2550 2950);
FORCEPROP 0 LAST ROOM PVDDQ_KLM
J 0
(-2550 3000);
DISPLAY 1.021277 (-2550 3000);
PAINT ORANGE (-2550 3000);
DISPLAY INVISIBLE (-2550 3000);
FORCEPROP 1 LAST PATH I76
J 0
(-2550 2950);
DISPLAY 0.978723 (-2550 2950);
PAINT WHITE (-2550 2950);
DISPLAY INVISIBLE (-2550 2950);
FORCEPROP 2 LAST CDS_LIB dev_discrete
J 0
(-2600 2800);
PAINT MONO (-2600 2800);
DISPLAY INVISIBLE (-2600 2800);
FORCEADD CAP_A..1
(-3000 2800);
FORCEPROP 1 LASTPIN (-3000 2900) $PN 1
J 0
(-2990 2880);
DISPLAY 0.787234 (-2990 2880);
PAINT ORANGE (-2990 2880);
FORCEPROP 1 LASTPIN (-3000 2700) $PN 2
J 0
(-2990 2680);
DISPLAY 0.787234 (-2990 2680);
PAINT ORANGE (-2990 2680);
FORCEPROP 1 LAST TOLERANCE 20%
J 0
(-2950 2750);
DISPLAY 0.617021 (-2950 2750);
PAINT SKYBLUE (-2950 2750);
FORCEPROP 1 LAST MATERIAL X6S
J 0
(-2950 2700);
DISPLAY 0.617021 (-2950 2700);
PAINT SKYBLUE (-2950 2700);
FORCEPROP 1 LAST VOLTAGE 4V
J 0
(-2950 2800);
DISPLAY 0.617021 (-2950 2800);
PAINT SKYBLUE (-2950 2800);
FORCEPROP 1 LAST LOCATION C5G99
J 0
(-2950 2900);
DISPLAY 0.617021 (-2950 2900);
PAINT AQUA (-2950 2900);
FORCEPROP 1 LAST VALUE 22.0UF
J 0
(-2950 2850);
DISPLAY 0.617021 (-2950 2850);
PAINT SKYBLUE (-2950 2850);
FORCEPROP 1 LAST PART_NUMBER E15431-004
J 0
(-2950 2650);
DISPLAY 0.617021 (-2950 2650);
PAINT BLUE (-2950 2650);
FORCEPROP 1 LAST PACK_TYPE 0603V
J 0
(-2950 2600);
DISPLAY 0.617021 (-2950 2600);
PAINT SKYBLUE (-2950 2600);
FORCEPROP 0 LAST GROUP PWR_MLCC_CAP
J 0
(-2944 2512);
DISPLAY 0.638298 (-2944 2512);
PAINT BROWN (-2944 2512);
DISPLAY BOTH (-2944 2512);
FORCEPROP 0 LAST BOM_DS NOPOP
J 0
(-2950 2550);
DISPLAY 0.638298 (-2950 2550);
PAINT BROWN (-2950 2550);
DISPLAY BOTH (-2950 2550);
FORCEPROP 2 LAST SEC_TYPE 0603V
J 0
(-2950 3000);
DISPLAY 1.021277 (-2950 3000);
PAINT ORANGE (-2950 3000);
DISPLAY INVISIBLE (-2950 3000);
FORCEPROP 0 LAST SEC 1
J 0
(-2950 2950);
DISPLAY 0.680851 (-2950 2950);
PAINT MONO (-2950 2950);
DISPLAY INVISIBLE (-2950 2950);
FORCEPROP 0 LAST ROOM PVDDQ_KLM
J 0
(-2950 3000);
DISPLAY 1.021277 (-2950 3000);
PAINT ORANGE (-2950 3000);
DISPLAY INVISIBLE (-2950 3000);
FORCEPROP 1 LAST PATH I77
J 0
(-2950 2950);
DISPLAY 0.978723 (-2950 2950);
PAINT WHITE (-2950 2950);
DISPLAY INVISIBLE (-2950 2950);
FORCEPROP 2 LAST CDS_LIB dev_discrete
J 0
(-3000 2800);
PAINT MONO (-3000 2800);
DISPLAY INVISIBLE (-3000 2800);
FORCEADD CAP_A..1
(-3400 2800);
FORCEPROP 1 LAST MATERIAL X6S
J 0
(-3350 2700);
DISPLAY 0.617021 (-3350 2700);
PAINT SKYBLUE (-3350 2700);
FORCEPROP 1 LAST VALUE 22.0UF
J 0
(-3350 2850);
DISPLAY 0.617021 (-3350 2850);
PAINT SKYBLUE (-3350 2850);
FORCEPROP 1 LAST LOCATION C5G98
J 0
(-3350 2900);
DISPLAY 0.617021 (-3350 2900);
PAINT AQUA (-3350 2900);
FORCEPROP 1 LAST PACK_TYPE 0603V
J 0
(-3350 2600);
DISPLAY 0.617021 (-3350 2600);
PAINT SKYBLUE (-3350 2600);
FORCEPROP 1 LASTPIN (-3400 2900) $PN 1
J 0
(-3390 2880);
DISPLAY 0.787234 (-3390 2880);
PAINT ORANGE (-3390 2880);
FORCEPROP 1 LAST VOLTAGE 4V
J 0
(-3350 2800);
DISPLAY 0.617021 (-3350 2800);
PAINT SKYBLUE (-3350 2800);
FORCEPROP 1 LASTPIN (-3400 2700) $PN 2
J 0
(-3390 2680);
DISPLAY 0.787234 (-3390 2680);
PAINT ORANGE (-3390 2680);
FORCEPROP 1 LAST PART_NUMBER E15431-004
J 0
(-3350 2650);
DISPLAY 0.617021 (-3350 2650);
PAINT BLUE (-3350 2650);
FORCEPROP 1 LAST TOLERANCE 20%
J 0
(-3350 2750);
DISPLAY 0.617021 (-3350 2750);
PAINT SKYBLUE (-3350 2750);
FORCEPROP 0 LAST GROUP PWR_MLCC_CAP
J 0
(-3344 2462);
DISPLAY 0.638298 (-3344 2462);
PAINT BROWN (-3344 2462);
DISPLAY BOTH (-3344 2462);
FORCEPROP 0 LAST BOM_DS NOPOP
J 0
(-3350 2550);
DISPLAY 0.638298 (-3350 2550);
PAINT BROWN (-3350 2550);
DISPLAY BOTH (-3350 2550);
FORCEPROP 2 LAST CDS_LIB dev_discrete
J 0
(-3400 2800);
PAINT MONO (-3400 2800);
DISPLAY INVISIBLE (-3400 2800);
FORCEPROP 1 LAST PATH I78
J 0
(-3350 2950);
DISPLAY 0.978723 (-3350 2950);
PAINT WHITE (-3350 2950);
DISPLAY INVISIBLE (-3350 2950);
FORCEPROP 0 LAST ROOM PVDDQ_KLM
J 0
(-3350 3000);
DISPLAY 1.021277 (-3350 3000);
PAINT ORANGE (-3350 3000);
DISPLAY INVISIBLE (-3350 3000);
FORCEPROP 0 LAST SEC 1
J 0
(-3350 2950);
DISPLAY 0.680851 (-3350 2950);
PAINT MONO (-3350 2950);
DISPLAY INVISIBLE (-3350 2950);
FORCEPROP 2 LAST SEC_TYPE 0603V
J 0
(-3350 3000);
DISPLAY 1.021277 (-3350 3000);
PAINT ORANGE (-3350 3000);
DISPLAY INVISIBLE (-3350 3000);
FORCEADD CAP_A..1
(-3800 2800);
FORCEPROP 1 LASTPIN (-3800 2900) $PN 1
J 0
(-3790 2880);
DISPLAY 0.787234 (-3790 2880);
PAINT ORANGE (-3790 2880);
FORCEPROP 1 LASTPIN (-3800 2700) $PN 2
J 0
(-3790 2680);
DISPLAY 0.787234 (-3790 2680);
PAINT ORANGE (-3790 2680);
FORCEPROP 1 LAST PACK_TYPE 0603V
J 0
(-3750 2600);
DISPLAY 0.617021 (-3750 2600);
PAINT SKYBLUE (-3750 2600);
FORCEPROP 1 LAST VALUE 22.0UF
J 0
(-3750 2850);
DISPLAY 0.617021 (-3750 2850);
PAINT SKYBLUE (-3750 2850);
FORCEPROP 1 LAST LOCATION C5G97
J 0
(-3750 2900);
DISPLAY 0.617021 (-3750 2900);
PAINT AQUA (-3750 2900);
FORCEPROP 1 LAST MATERIAL X6S
J 0
(-3750 2700);
DISPLAY 0.617021 (-3750 2700);
PAINT SKYBLUE (-3750 2700);
FORCEPROP 1 LAST TOLERANCE 20%
J 0
(-3750 2750);
DISPLAY 0.617021 (-3750 2750);
PAINT SKYBLUE (-3750 2750);
FORCEPROP 1 LAST VOLTAGE 4V
J 0
(-3750 2800);
DISPLAY 0.617021 (-3750 2800);
PAINT SKYBLUE (-3750 2800);
FORCEPROP 1 LAST PART_NUMBER E15431-004
J 0
(-3750 2650);
DISPLAY 0.617021 (-3750 2650);
PAINT BLUE (-3750 2650);
FORCEPROP 0 LAST GROUP PWR_MLCC_CAP
J 0
(-3744 2512);
DISPLAY 0.638298 (-3744 2512);
PAINT BROWN (-3744 2512);
DISPLAY BOTH (-3744 2512);
FORCEPROP 0 LAST BOM_DS NOPOP
J 0
(-3750 2550);
DISPLAY 0.638298 (-3750 2550);
PAINT BROWN (-3750 2550);
DISPLAY BOTH (-3750 2550);
FORCEPROP 2 LAST SEC_TYPE 0603V
J 0
(-3750 3000);
DISPLAY 1.021277 (-3750 3000);
PAINT ORANGE (-3750 3000);
DISPLAY INVISIBLE (-3750 3000);
FORCEPROP 0 LAST SEC 1
J 0
(-3750 2950);
DISPLAY 0.680851 (-3750 2950);
PAINT MONO (-3750 2950);
DISPLAY INVISIBLE (-3750 2950);
FORCEPROP 0 LAST ROOM PVDDQ_KLM
J 0
(-3750 3000);
DISPLAY 1.021277 (-3750 3000);
PAINT ORANGE (-3750 3000);
DISPLAY INVISIBLE (-3750 3000);
FORCEPROP 1 LAST PATH I79
J 0
(-3750 2950);
DISPLAY 0.978723 (-3750 2950);
PAINT WHITE (-3750 2950);
DISPLAY INVISIBLE (-3750 2950);
FORCEPROP 2 LAST CDS_LIB dev_discrete
J 0
(-3800 2800);
PAINT MONO (-3800 2800);
DISPLAY INVISIBLE (-3800 2800);
FORCEADD PVDDQ_GHJ..1
(-7750 3100);
FORCEPROP 3 LASTPIN (-7750 3050) SIG_NAME PVDDQ_GHJ\g
J 0
(-7740 3060);
DISPLAY 0.659574 (-7740 3060);
PAINT MONO (-7740 3060);
DISPLAY INVISIBLE (-7740 3060);
FORCEPROP 1 LAST HDL_POWER PVDDQ_GHJ
J 1
(-7750 3150);
DISPLAY 0.872340 (-7750 3150);
PAINT GREEN (-7750 3150);
DISPLAY INVISIBLE (-7750 3150);
FORCEPROP 1 LAST BODY_TYPE PLUMBING
J 0
(-7795 3057);
DISPLAY 0.340426 (-7795 3057);
PAINT GREEN (-7795 3057);
DISPLAY INVISIBLE (-7795 3057);
FORCEPROP 2 LAST CDS_LIB mstr_symbols
J 0
(-7750 3100);
PAINT MONO (-7750 3100);
DISPLAY INVISIBLE (-7750 3100);
FORCEPROP 1 LAST VOLTAGE 1.2V
J 0
(-7795 3057);
DISPLAY 0.340426 (-7795 3057);
PAINT SKYBLUE (-7795 3057);
DISPLAY INVISIBLE (-7795 3057);
FORCEPROP 1 LAST PATH I8
J 0
(-7700 3125);
DISPLAY 0.872340 (-7700 3125);
PAINT AQUA (-7700 3125);
DISPLAY INVISIBLE (-7700 3125);
FORCEADD CAP_A..1
(-600 1850);
FORCEPROP 0 LAST BOM_DS NOPOP
J 0
(-550 1600);
DISPLAY 0.638298 (-550 1600);
PAINT BROWN (-550 1600);
DISPLAY BOTH (-550 1600);
FORCEPROP 0 LAST GROUP PWR_MLCC_CAP
J 0
(-544 1562);
DISPLAY 0.638298 (-544 1562);
PAINT BROWN (-544 1562);
DISPLAY BOTH (-544 1562);
FORCEPROP 1 LAST VOLTAGE 4V
J 0
(-550 1850);
DISPLAY 0.617021 (-550 1850);
PAINT SKYBLUE (-550 1850);
FORCEPROP 1 LAST VALUE 22.0UF
J 0
(-550 1900);
DISPLAY 0.617021 (-550 1900);
PAINT SKYBLUE (-550 1900);
FORCEPROP 1 LAST LOCATION C5G114
J 0
(-550 1950);
DISPLAY 0.617021 (-550 1950);
PAINT AQUA (-550 1950);
FORCEPROP 1 LAST PART_NUMBER E15431-004
J 0
(-550 1700);
DISPLAY 0.617021 (-550 1700);
PAINT BLUE (-550 1700);
FORCEPROP 1 LAST TOLERANCE 20%
J 0
(-550 1800);
DISPLAY 0.617021 (-550 1800);
PAINT SKYBLUE (-550 1800);
FORCEPROP 1 LAST PACK_TYPE 0603V
J 0
(-550 1650);
DISPLAY 0.617021 (-550 1650);
PAINT SKYBLUE (-550 1650);
FORCEPROP 1 LASTPIN (-600 1750) $PN 2
J 0
(-590 1730);
DISPLAY 0.787234 (-590 1730);
PAINT ORANGE (-590 1730);
FORCEPROP 1 LASTPIN (-600 1950) $PN 1
J 0
(-590 1930);
DISPLAY 0.787234 (-590 1930);
PAINT ORANGE (-590 1930);
FORCEPROP 1 LAST MATERIAL X6S
J 0
(-550 1750);
DISPLAY 0.617021 (-550 1750);
PAINT SKYBLUE (-550 1750);
FORCEPROP 0 LAST ROOM PVDDQ_KLM
J 0
(-550 2050);
DISPLAY 1.021277 (-550 2050);
PAINT ORANGE (-550 2050);
DISPLAY INVISIBLE (-550 2050);
FORCEPROP 1 LAST PATH I80
J 0
(-550 2000);
DISPLAY 0.978723 (-550 2000);
PAINT WHITE (-550 2000);
DISPLAY INVISIBLE (-550 2000);
FORCEPROP 2 LAST CDS_LIB dev_discrete
J 0
(-600 1850);
PAINT MONO (-600 1850);
DISPLAY INVISIBLE (-600 1850);
FORCEPROP 0 LAST SEC 1
J 0
(-550 2000);
DISPLAY 0.680851 (-550 2000);
PAINT MONO (-550 2000);
DISPLAY INVISIBLE (-550 2000);
FORCEPROP 2 LAST SEC_TYPE 0603V
J 0
(-550 2050);
DISPLAY 1.021277 (-550 2050);
PAINT ORANGE (-550 2050);
DISPLAY INVISIBLE (-550 2050);
FORCEADD CAP_A..1
(-1000 1850);
FORCEPROP 0 LAST BOM_DS NOPOP
J 0
(-950 1600);
DISPLAY 0.638298 (-950 1600);
PAINT BROWN (-950 1600);
DISPLAY BOTH (-950 1600);
FORCEPROP 1 LAST MATERIAL X6S
J 0
(-950 1750);
DISPLAY 0.617021 (-950 1750);
PAINT SKYBLUE (-950 1750);
FORCEPROP 1 LAST PART_NUMBER E15431-004
J 0
(-950 1700);
DISPLAY 0.617021 (-950 1700);
PAINT BLUE (-950 1700);
FORCEPROP 0 LAST GROUP PWR_MLCC_CAP
J 0
(-944 1512);
DISPLAY 0.638298 (-944 1512);
PAINT BROWN (-944 1512);
DISPLAY BOTH (-944 1512);
FORCEPROP 1 LASTPIN (-1000 1750) $PN 2
J 0
(-990 1730);
DISPLAY 0.787234 (-990 1730);
PAINT ORANGE (-990 1730);
FORCEPROP 1 LASTPIN (-1000 1950) $PN 1
J 0
(-990 1930);
DISPLAY 0.787234 (-990 1930);
PAINT ORANGE (-990 1930);
FORCEPROP 1 LAST PACK_TYPE 0603V
J 0
(-950 1650);
DISPLAY 0.617021 (-950 1650);
PAINT SKYBLUE (-950 1650);
FORCEPROP 1 LAST TOLERANCE 20%
J 0
(-950 1800);
DISPLAY 0.617021 (-950 1800);
PAINT SKYBLUE (-950 1800);
FORCEPROP 1 LAST LOCATION C5G113
J 0
(-950 1950);
DISPLAY 0.617021 (-950 1950);
PAINT AQUA (-950 1950);
FORCEPROP 1 LAST VALUE 22.0UF
J 0
(-950 1900);
DISPLAY 0.617021 (-950 1900);
PAINT SKYBLUE (-950 1900);
FORCEPROP 1 LAST VOLTAGE 4V
J 0
(-950 1850);
DISPLAY 0.617021 (-950 1850);
PAINT SKYBLUE (-950 1850);
FORCEPROP 2 LAST SEC_TYPE 0603V
J 0
(-950 2050);
DISPLAY 1.021277 (-950 2050);
PAINT ORANGE (-950 2050);
DISPLAY INVISIBLE (-950 2050);
FORCEPROP 0 LAST SEC 1
J 0
(-950 2000);
DISPLAY 0.680851 (-950 2000);
PAINT MONO (-950 2000);
DISPLAY INVISIBLE (-950 2000);
FORCEPROP 2 LAST CDS_LIB dev_discrete
J 0
(-1000 1850);
PAINT MONO (-1000 1850);
DISPLAY INVISIBLE (-1000 1850);
FORCEPROP 1 LAST PATH I81
J 0
(-950 2000);
DISPLAY 0.978723 (-950 2000);
PAINT WHITE (-950 2000);
DISPLAY INVISIBLE (-950 2000);
FORCEPROP 0 LAST ROOM PVDDQ_KLM
J 0
(-950 2050);
DISPLAY 1.021277 (-950 2050);
PAINT ORANGE (-950 2050);
DISPLAY INVISIBLE (-950 2050);
FORCEADD CAP_A..1
(-1400 1850);
FORCEPROP 0 LAST BOM_DS NOPOP
J 0
(-1350 1600);
DISPLAY 0.638298 (-1350 1600);
PAINT BROWN (-1350 1600);
DISPLAY BOTH (-1350 1600);
FORCEPROP 1 LAST LOCATION C5G112
J 0
(-1350 1950);
DISPLAY 0.617021 (-1350 1950);
PAINT AQUA (-1350 1950);
FORCEPROP 1 LAST TOLERANCE 20%
J 0
(-1350 1800);
DISPLAY 0.617021 (-1350 1800);
PAINT SKYBLUE (-1350 1800);
FORCEPROP 1 LAST VOLTAGE 4V
J 0
(-1350 1850);
DISPLAY 0.617021 (-1350 1850);
PAINT SKYBLUE (-1350 1850);
FORCEPROP 1 LAST MATERIAL X6S
J 0
(-1350 1750);
DISPLAY 0.617021 (-1350 1750);
PAINT SKYBLUE (-1350 1750);
FORCEPROP 1 LASTPIN (-1400 1750) $PN 2
J 0
(-1390 1730);
DISPLAY 0.787234 (-1390 1730);
PAINT ORANGE (-1390 1730);
FORCEPROP 1 LASTPIN (-1400 1950) $PN 1
J 0
(-1390 1930);
DISPLAY 0.787234 (-1390 1930);
PAINT ORANGE (-1390 1930);
FORCEPROP 1 LAST VALUE 22.0UF
J 0
(-1350 1900);
DISPLAY 0.617021 (-1350 1900);
PAINT SKYBLUE (-1350 1900);
FORCEPROP 1 LAST PART_NUMBER E15431-004
J 0
(-1350 1700);
DISPLAY 0.617021 (-1350 1700);
PAINT BLUE (-1350 1700);
FORCEPROP 1 LAST PACK_TYPE 0603V
J 0
(-1350 1650);
DISPLAY 0.617021 (-1350 1650);
PAINT SKYBLUE (-1350 1650);
FORCEPROP 0 LAST GROUP PWR_MLCC_CAP
J 0
(-1344 1562);
DISPLAY 0.638298 (-1344 1562);
PAINT BROWN (-1344 1562);
DISPLAY BOTH (-1344 1562);
FORCEPROP 0 LAST ROOM PVDDQ_KLM
J 0
(-1350 2050);
DISPLAY 1.021277 (-1350 2050);
PAINT ORANGE (-1350 2050);
DISPLAY INVISIBLE (-1350 2050);
FORCEPROP 1 LAST PATH I82
J 0
(-1350 2000);
DISPLAY 0.978723 (-1350 2000);
PAINT WHITE (-1350 2000);
DISPLAY INVISIBLE (-1350 2000);
FORCEPROP 2 LAST CDS_LIB dev_discrete
J 0
(-1400 1850);
PAINT MONO (-1400 1850);
DISPLAY INVISIBLE (-1400 1850);
FORCEPROP 0 LAST SEC 1
J 0
(-1350 2000);
DISPLAY 0.680851 (-1350 2000);
PAINT MONO (-1350 2000);
DISPLAY INVISIBLE (-1350 2000);
FORCEPROP 2 LAST SEC_TYPE 0603V
J 0
(-1350 2050);
DISPLAY 1.021277 (-1350 2050);
PAINT ORANGE (-1350 2050);
DISPLAY INVISIBLE (-1350 2050);
FORCEADD CAP_A..1
(-1800 1850);
FORCEPROP 0 LAST BOM_DS NOPOP
J 0
(-1750 1600);
DISPLAY 0.638298 (-1750 1600);
PAINT BROWN (-1750 1600);
DISPLAY BOTH (-1750 1600);
FORCEPROP 1 LAST TOLERANCE 20%
J 0
(-1750 1800);
DISPLAY 0.617021 (-1750 1800);
PAINT SKYBLUE (-1750 1800);
FORCEPROP 1 LAST VOLTAGE 4V
J 0
(-1750 1850);
DISPLAY 0.617021 (-1750 1850);
PAINT SKYBLUE (-1750 1850);
FORCEPROP 1 LAST LOCATION C5G111
J 0
(-1750 1950);
DISPLAY 0.617021 (-1750 1950);
PAINT AQUA (-1750 1950);
FORCEPROP 1 LASTPIN (-1800 1950) $PN 1
J 0
(-1790 1930);
DISPLAY 0.787234 (-1790 1930);
PAINT ORANGE (-1790 1930);
FORCEPROP 1 LAST VALUE 22.0UF
J 0
(-1750 1900);
DISPLAY 0.617021 (-1750 1900);
PAINT SKYBLUE (-1750 1900);
FORCEPROP 1 LAST MATERIAL X6S
J 0
(-1750 1750);
DISPLAY 0.617021 (-1750 1750);
PAINT SKYBLUE (-1750 1750);
FORCEPROP 1 LAST PART_NUMBER E15431-004
J 0
(-1750 1700);
DISPLAY 0.617021 (-1750 1700);
PAINT BLUE (-1750 1700);
FORCEPROP 1 LAST PACK_TYPE 0603V
J 0
(-1750 1650);
DISPLAY 0.617021 (-1750 1650);
PAINT SKYBLUE (-1750 1650);
FORCEPROP 1 LASTPIN (-1800 1750) $PN 2
J 0
(-1790 1730);
DISPLAY 0.787234 (-1790 1730);
PAINT ORANGE (-1790 1730);
FORCEPROP 0 LAST GROUP PWR_MLCC_CAP
J 0
(-1744 1487);
DISPLAY 0.638298 (-1744 1487);
PAINT BROWN (-1744 1487);
DISPLAY BOTH (-1744 1487);
FORCEPROP 2 LAST SEC_TYPE 0603V
J 0
(-1750 2050);
DISPLAY 1.021277 (-1750 2050);
PAINT ORANGE (-1750 2050);
DISPLAY INVISIBLE (-1750 2050);
FORCEPROP 0 LAST SEC 1
J 0
(-1750 2000);
DISPLAY 0.680851 (-1750 2000);
PAINT MONO (-1750 2000);
DISPLAY INVISIBLE (-1750 2000);
FORCEPROP 2 LAST CDS_LIB dev_discrete
J 0
(-1800 1850);
PAINT MONO (-1800 1850);
DISPLAY INVISIBLE (-1800 1850);
FORCEPROP 1 LAST PATH I83
J 0
(-1750 2000);
DISPLAY 0.978723 (-1750 2000);
PAINT WHITE (-1750 2000);
DISPLAY INVISIBLE (-1750 2000);
FORCEPROP 0 LAST ROOM PVDDQ_KLM
J 0
(-1750 2050);
DISPLAY 1.021277 (-1750 2050);
PAINT ORANGE (-1750 2050);
DISPLAY INVISIBLE (-1750 2050);
FORCEADD CAP_A..1
(-2200 1850);
FORCEPROP 0 LAST BOM_DS NOPOP
J 0
(-2150 1600);
DISPLAY 0.638298 (-2150 1600);
PAINT BROWN (-2150 1600);
DISPLAY BOTH (-2150 1600);
FORCEPROP 1 LAST TOLERANCE 20%
J 0
(-2150 1800);
DISPLAY 0.617021 (-2150 1800);
PAINT SKYBLUE (-2150 1800);
FORCEPROP 1 LAST VOLTAGE 4V
J 0
(-2150 1850);
DISPLAY 0.617021 (-2150 1850);
PAINT SKYBLUE (-2150 1850);
FORCEPROP 1 LAST LOCATION C5G110
J 0
(-2150 1950);
DISPLAY 0.617021 (-2150 1950);
PAINT AQUA (-2150 1950);
FORCEPROP 1 LAST VALUE 22.0UF
J 0
(-2150 1900);
DISPLAY 0.617021 (-2150 1900);
PAINT SKYBLUE (-2150 1900);
FORCEPROP 1 LAST MATERIAL X6S
J 0
(-2150 1750);
DISPLAY 0.617021 (-2150 1750);
PAINT SKYBLUE (-2150 1750);
FORCEPROP 1 LAST PACK_TYPE 0603V
J 0
(-2150 1650);
DISPLAY 0.617021 (-2150 1650);
PAINT SKYBLUE (-2150 1650);
FORCEPROP 1 LASTPIN (-2200 1750) $PN 2
J 0
(-2190 1730);
DISPLAY 0.787234 (-2190 1730);
PAINT ORANGE (-2190 1730);
FORCEPROP 1 LASTPIN (-2200 1950) $PN 1
J 0
(-2190 1930);
DISPLAY 0.787234 (-2190 1930);
PAINT ORANGE (-2190 1930);
FORCEPROP 1 LAST PART_NUMBER E15431-004
J 0
(-2150 1700);
DISPLAY 0.617021 (-2150 1700);
PAINT BLUE (-2150 1700);
FORCEPROP 0 LAST GROUP PWR_MLCC_CAP
J 0
(-2144 1562);
DISPLAY 0.638298 (-2144 1562);
PAINT BROWN (-2144 1562);
DISPLAY BOTH (-2144 1562);
FORCEPROP 0 LAST ROOM PVDDQ_KLM
J 0
(-2150 2050);
DISPLAY 1.021277 (-2150 2050);
PAINT ORANGE (-2150 2050);
DISPLAY INVISIBLE (-2150 2050);
FORCEPROP 1 LAST PATH I84
J 0
(-2150 2000);
DISPLAY 0.978723 (-2150 2000);
PAINT WHITE (-2150 2000);
DISPLAY INVISIBLE (-2150 2000);
FORCEPROP 2 LAST CDS_LIB dev_discrete
J 0
(-2200 1850);
PAINT MONO (-2200 1850);
DISPLAY INVISIBLE (-2200 1850);
FORCEPROP 0 LAST SEC 1
J 0
(-2150 2000);
DISPLAY 0.680851 (-2150 2000);
PAINT MONO (-2150 2000);
DISPLAY INVISIBLE (-2150 2000);
FORCEPROP 2 LAST SEC_TYPE 0603V
J 0
(-2150 2050);
DISPLAY 1.021277 (-2150 2050);
PAINT ORANGE (-2150 2050);
DISPLAY INVISIBLE (-2150 2050);
FORCEADD CAP_A..1
(-2600 1850);
FORCEPROP 0 LAST BOM_DS NOPOP
J 0
(-2550 1600);
DISPLAY 0.638298 (-2550 1600);
PAINT BROWN (-2550 1600);
DISPLAY BOTH (-2550 1600);
FORCEPROP 1 LAST VOLTAGE 4V
J 0
(-2550 1850);
DISPLAY 0.617021 (-2550 1850);
PAINT SKYBLUE (-2550 1850);
FORCEPROP 1 LAST PACK_TYPE 0603V
J 0
(-2550 1650);
DISPLAY 0.617021 (-2550 1650);
PAINT SKYBLUE (-2550 1650);
FORCEPROP 1 LAST PART_NUMBER E15431-004
J 0
(-2550 1700);
DISPLAY 0.617021 (-2550 1700);
PAINT BLUE (-2550 1700);
FORCEPROP 1 LASTPIN (-2600 1950) $PN 1
J 0
(-2590 1930);
DISPLAY 0.787234 (-2590 1930);
PAINT ORANGE (-2590 1930);
FORCEPROP 1 LASTPIN (-2600 1750) $PN 2
J 0
(-2590 1730);
DISPLAY 0.787234 (-2590 1730);
PAINT ORANGE (-2590 1730);
FORCEPROP 1 LAST TOLERANCE 20%
J 0
(-2550 1800);
DISPLAY 0.617021 (-2550 1800);
PAINT SKYBLUE (-2550 1800);
FORCEPROP 1 LAST MATERIAL X6S
J 0
(-2550 1750);
DISPLAY 0.617021 (-2550 1750);
PAINT SKYBLUE (-2550 1750);
FORCEPROP 1 LAST LOCATION C5G109
J 0
(-2550 1950);
DISPLAY 0.617021 (-2550 1950);
PAINT AQUA (-2550 1950);
FORCEPROP 1 LAST VALUE 22.0UF
J 0
(-2550 1900);
DISPLAY 0.617021 (-2550 1900);
PAINT SKYBLUE (-2550 1900);
FORCEPROP 0 LAST GROUP PWR_MLCC_CAP
J 0
(-2544 1512);
DISPLAY 0.638298 (-2544 1512);
PAINT BROWN (-2544 1512);
DISPLAY BOTH (-2544 1512);
FORCEPROP 2 LAST SEC_TYPE 0603V
J 0
(-2550 2050);
DISPLAY 1.021277 (-2550 2050);
PAINT ORANGE (-2550 2050);
DISPLAY INVISIBLE (-2550 2050);
FORCEPROP 0 LAST SEC 1
J 0
(-2550 2000);
DISPLAY 0.680851 (-2550 2000);
PAINT MONO (-2550 2000);
DISPLAY INVISIBLE (-2550 2000);
FORCEPROP 2 LAST CDS_LIB dev_discrete
J 0
(-2600 1850);
PAINT MONO (-2600 1850);
DISPLAY INVISIBLE (-2600 1850);
FORCEPROP 1 LAST PATH I85
J 0
(-2550 2000);
DISPLAY 0.978723 (-2550 2000);
PAINT WHITE (-2550 2000);
DISPLAY INVISIBLE (-2550 2000);
FORCEPROP 0 LAST ROOM PVDDQ_KLM
J 0
(-2550 2050);
DISPLAY 1.021277 (-2550 2050);
PAINT ORANGE (-2550 2050);
DISPLAY INVISIBLE (-2550 2050);
FORCEADD CAP_A..1
(-3000 1850);
FORCEPROP 0 LAST BOM_DS NOPOP
J 0
(-2950 1600);
DISPLAY 0.638298 (-2950 1600);
PAINT BROWN (-2950 1600);
DISPLAY BOTH (-2950 1600);
FORCEPROP 1 LAST LOCATION C5G108
J 0
(-2950 1950);
DISPLAY 0.617021 (-2950 1950);
PAINT AQUA (-2950 1950);
FORCEPROP 1 LAST PACK_TYPE 0603V
J 0
(-2950 1650);
DISPLAY 0.617021 (-2950 1650);
PAINT SKYBLUE (-2950 1650);
FORCEPROP 1 LAST TOLERANCE 20%
J 0
(-2950 1800);
DISPLAY 0.617021 (-2950 1800);
PAINT SKYBLUE (-2950 1800);
FORCEPROP 1 LAST VOLTAGE 4V
J 0
(-2950 1850);
DISPLAY 0.617021 (-2950 1850);
PAINT SKYBLUE (-2950 1850);
FORCEPROP 1 LAST VALUE 22.0UF
J 0
(-2950 1900);
DISPLAY 0.617021 (-2950 1900);
PAINT SKYBLUE (-2950 1900);
FORCEPROP 1 LAST MATERIAL X6S
J 0
(-2950 1750);
DISPLAY 0.617021 (-2950 1750);
PAINT SKYBLUE (-2950 1750);
FORCEPROP 1 LASTPIN (-3000 1750) $PN 2
J 0
(-2990 1730);
DISPLAY 0.787234 (-2990 1730);
PAINT ORANGE (-2990 1730);
FORCEPROP 1 LASTPIN (-3000 1950) $PN 1
J 0
(-2990 1930);
DISPLAY 0.787234 (-2990 1930);
PAINT ORANGE (-2990 1930);
FORCEPROP 1 LAST PART_NUMBER E15431-004
J 0
(-2950 1700);
DISPLAY 0.617021 (-2950 1700);
PAINT BLUE (-2950 1700);
FORCEPROP 0 LAST GROUP PWR_MLCC_CAP
J 0
(-2944 1562);
DISPLAY 0.638298 (-2944 1562);
PAINT BROWN (-2944 1562);
DISPLAY BOTH (-2944 1562);
FORCEPROP 0 LAST ROOM PVDDQ_KLM
J 0
(-2950 2050);
DISPLAY 1.021277 (-2950 2050);
PAINT ORANGE (-2950 2050);
DISPLAY INVISIBLE (-2950 2050);
FORCEPROP 1 LAST PATH I86
J 0
(-2950 2000);
DISPLAY 0.978723 (-2950 2000);
PAINT WHITE (-2950 2000);
DISPLAY INVISIBLE (-2950 2000);
FORCEPROP 2 LAST CDS_LIB dev_discrete
J 0
(-3000 1850);
PAINT MONO (-3000 1850);
DISPLAY INVISIBLE (-3000 1850);
FORCEPROP 0 LAST SEC 1
J 0
(-2950 2000);
DISPLAY 0.680851 (-2950 2000);
PAINT MONO (-2950 2000);
DISPLAY INVISIBLE (-2950 2000);
FORCEPROP 2 LAST SEC_TYPE 0603V
J 0
(-2950 2050);
DISPLAY 1.021277 (-2950 2050);
PAINT ORANGE (-2950 2050);
DISPLAY INVISIBLE (-2950 2050);
FORCEADD CAP_A..1
(-3400 1850);
FORCEPROP 0 LAST BOM_DS NOPOP
J 0
(-3350 1600);
DISPLAY 0.638298 (-3350 1600);
PAINT BROWN (-3350 1600);
DISPLAY BOTH (-3350 1600);
FORCEPROP 1 LAST VOLTAGE 4V
J 0
(-3350 1850);
DISPLAY 0.617021 (-3350 1850);
PAINT SKYBLUE (-3350 1850);
FORCEPROP 1 LAST VALUE 22.0UF
J 0
(-3350 1900);
DISPLAY 0.617021 (-3350 1900);
PAINT SKYBLUE (-3350 1900);
FORCEPROP 1 LAST PACK_TYPE 0603V
J 0
(-3350 1650);
DISPLAY 0.617021 (-3350 1650);
PAINT SKYBLUE (-3350 1650);
FORCEPROP 1 LAST LOCATION C5G107
J 0
(-3350 1950);
DISPLAY 0.617021 (-3350 1950);
PAINT AQUA (-3350 1950);
FORCEPROP 1 LAST TOLERANCE 20%
J 0
(-3350 1800);
DISPLAY 0.617021 (-3350 1800);
PAINT SKYBLUE (-3350 1800);
FORCEPROP 1 LAST MATERIAL X6S
J 0
(-3350 1750);
DISPLAY 0.617021 (-3350 1750);
PAINT SKYBLUE (-3350 1750);
FORCEPROP 1 LAST PART_NUMBER E15431-004
J 0
(-3350 1700);
DISPLAY 0.617021 (-3350 1700);
PAINT BLUE (-3350 1700);
FORCEPROP 1 LASTPIN (-3400 1950) $PN 1
J 0
(-3390 1930);
DISPLAY 0.787234 (-3390 1930);
PAINT ORANGE (-3390 1930);
FORCEPROP 1 LASTPIN (-3400 1750) $PN 2
J 0
(-3390 1730);
DISPLAY 0.787234 (-3390 1730);
PAINT ORANGE (-3390 1730);
FORCEPROP 0 LAST GROUP PWR_MLCC_CAP
J 0
(-3344 1512);
DISPLAY 0.638298 (-3344 1512);
PAINT BROWN (-3344 1512);
DISPLAY BOTH (-3344 1512);
FORCEPROP 2 LAST SEC_TYPE 0603V
J 0
(-3350 2050);
DISPLAY 1.021277 (-3350 2050);
PAINT ORANGE (-3350 2050);
DISPLAY INVISIBLE (-3350 2050);
FORCEPROP 0 LAST SEC 1
J 0
(-3350 2000);
DISPLAY 0.680851 (-3350 2000);
PAINT MONO (-3350 2000);
DISPLAY INVISIBLE (-3350 2000);
FORCEPROP 2 LAST CDS_LIB dev_discrete
J 0
(-3400 1850);
PAINT MONO (-3400 1850);
DISPLAY INVISIBLE (-3400 1850);
FORCEPROP 1 LAST PATH I87
J 0
(-3350 2000);
DISPLAY 0.978723 (-3350 2000);
PAINT WHITE (-3350 2000);
DISPLAY INVISIBLE (-3350 2000);
FORCEPROP 0 LAST ROOM PVDDQ_KLM
J 0
(-3350 2050);
DISPLAY 1.021277 (-3350 2050);
PAINT ORANGE (-3350 2050);
DISPLAY INVISIBLE (-3350 2050);
FORCEADD CAP_A..1
(-3800 1850);
FORCEPROP 0 LAST BOM_DS NOPOP
J 0
(-3750 1600);
DISPLAY 0.638298 (-3750 1600);
PAINT BROWN (-3750 1600);
DISPLAY BOTH (-3750 1600);
FORCEPROP 1 LAST PART_NUMBER E15431-004
J 0
(-3750 1700);
DISPLAY 0.617021 (-3750 1700);
PAINT BLUE (-3750 1700);
FORCEPROP 1 LAST LOCATION C5G106
J 0
(-3750 1950);
DISPLAY 0.617021 (-3750 1950);
PAINT AQUA (-3750 1950);
FORCEPROP 1 LAST TOLERANCE 20%
J 0
(-3750 1800);
DISPLAY 0.617021 (-3750 1800);
PAINT SKYBLUE (-3750 1800);
FORCEPROP 1 LAST PACK_TYPE 0603V
J 0
(-3750 1650);
DISPLAY 0.617021 (-3750 1650);
PAINT SKYBLUE (-3750 1650);
FORCEPROP 1 LAST VALUE 22.0UF
J 0
(-3750 1900);
DISPLAY 0.617021 (-3750 1900);
PAINT SKYBLUE (-3750 1900);
FORCEPROP 1 LAST VOLTAGE 4V
J 0
(-3750 1850);
DISPLAY 0.617021 (-3750 1850);
PAINT SKYBLUE (-3750 1850);
FORCEPROP 1 LASTPIN (-3800 1750) $PN 2
J 0
(-3790 1730);
DISPLAY 0.787234 (-3790 1730);
PAINT ORANGE (-3790 1730);
FORCEPROP 1 LASTPIN (-3800 1950) $PN 1
J 0
(-3790 1930);
DISPLAY 0.787234 (-3790 1930);
PAINT ORANGE (-3790 1930);
FORCEPROP 1 LAST MATERIAL X6S
J 0
(-3750 1750);
DISPLAY 0.617021 (-3750 1750);
PAINT SKYBLUE (-3750 1750);
FORCEPROP 0 LAST GROUP PWR_MLCC_CAP
J 0
(-3744 1562);
DISPLAY 0.638298 (-3744 1562);
PAINT BROWN (-3744 1562);
DISPLAY BOTH (-3744 1562);
FORCEPROP 0 LAST ROOM PVDDQ_KLM
J 0
(-3750 2050);
DISPLAY 1.021277 (-3750 2050);
PAINT ORANGE (-3750 2050);
DISPLAY INVISIBLE (-3750 2050);
FORCEPROP 1 LAST PATH I88
J 0
(-3750 2000);
DISPLAY 0.978723 (-3750 2000);
PAINT WHITE (-3750 2000);
DISPLAY INVISIBLE (-3750 2000);
FORCEPROP 2 LAST CDS_LIB dev_discrete
J 0
(-3800 1850);
PAINT MONO (-3800 1850);
DISPLAY INVISIBLE (-3800 1850);
FORCEPROP 0 LAST SEC 1
J 0
(-3750 2000);
DISPLAY 0.680851 (-3750 2000);
PAINT MONO (-3750 2000);
DISPLAY INVISIBLE (-3750 2000);
FORCEPROP 2 LAST SEC_TYPE 0603V
J 0
(-3750 2050);
DISPLAY 1.021277 (-3750 2050);
PAINT ORANGE (-3750 2050);
DISPLAY INVISIBLE (-3750 2050);
FORCEADD CAP..1
(-3800 3775);
FORCEPROP 0 LAST GROUP PWR_MLCC_CAP
J 0
(-3744 3487);
DISPLAY 0.638298 (-3744 3487);
PAINT BROWN (-3744 3487);
DISPLAY BOTH (-3744 3487);
FORCEPROP 1 LAST PART_NUMBER C95333-006
J 0
(-3750 3575);
DISPLAY 0.617021 (-3750 3575);
PAINT BLUE (-3750 3575);
FORCEPROP 1 LAST PACK_TYPE 0805
J 0
(-3750 3625);
DISPLAY 0.617021 (-3750 3625);
PAINT SKYBLUE (-3750 3625);
FORCEPROP 1 LAST MATERIAL X6S
J 0
(-3750 3675);
DISPLAY 0.617021 (-3750 3675);
PAINT SKYBLUE (-3750 3675);
FORCEPROP 1 LAST TOLERANCE 20%
J 0
(-3750 3725);
DISPLAY 0.617021 (-3750 3725);
PAINT SKYBLUE (-3750 3725);
FORCEPROP 1 LAST LOCATION C5G115
J 0
(-3750 3875);
DISPLAY 0.617021 (-3750 3875);
PAINT AQUA (-3750 3875);
FORCEPROP 1 LAST VALUE 47UF
J 0
(-3750 3825);
DISPLAY 0.617021 (-3750 3825);
PAINT SKYBLUE (-3750 3825);
FORCEPROP 1 LAST VOLTAGE 4V
J 0
(-3750 3775);
DISPLAY 0.638298 (-3750 3775);
PAINT SKYBLUE (-3750 3775);
FORCEPROP 0 LAST POP NOPOP
J 0
(-3750 3525);
DISPLAY 0.638298 (-3750 3525);
PAINT RED (-3750 3525);
FORCEPROP 1 LASTPIN (-3800 3675) $PN 2
J 0
(-3790 3655);
DISPLAY 0.787234 (-3790 3655);
PAINT ORANGE (-3790 3655);
FORCEPROP 1 LASTPIN (-3800 3875) $PN 1
J 0
(-3790 3855);
DISPLAY 0.787234 (-3790 3855);
PAINT ORANGE (-3790 3855);
FORCEPROP 2 LAST CDS_LIB mstr_discrete
J 0
(-3800 3775);
PAINT MONO (-3800 3775);
DISPLAY INVISIBLE (-3800 3775);
FORCEPROP 1 LAST PATH I89
J 0
(-3750 3925);
DISPLAY 0.978723 (-3750 3925);
PAINT WHITE (-3750 3925);
DISPLAY INVISIBLE (-3750 3925);
FORCEPROP 2 LAST ROOM PVCCIN_CPU0_DECAP_VR
J 0
(-3750 3925);
DISPLAY 1.021277 (-3750 3925);
PAINT ORANGE (-3750 3925);
DISPLAY INVISIBLE (-3750 3925);
FORCEPROP 2 LAST BOM_COST PROC_SOCKET
J 0
(-3750 3975);
DISPLAY 1.021277 (-3750 3975);
PAINT ORANGE (-3750 3975);
DISPLAY INVISIBLE (-3750 3975);
FORCEPROP 0 LAST SEC 1
J 0
(-3750 3925);
DISPLAY 0.680851 (-3750 3925);
PAINT MONO (-3750 3925);
DISPLAY INVISIBLE (-3750 3925);
FORCEPROP 2 LAST SEC_TYPE 0805
J 0
(-3750 3975);
DISPLAY 1.021277 (-3750 3975);
PAINT ORANGE (-3750 3975);
DISPLAY INVISIBLE (-3750 3975);
FORCEADD CAP..1
(-3400 3775);
FORCEPROP 1 LAST LOCATION C5G116
J 0
(-3350 3875);
DISPLAY 0.617021 (-3350 3875);
PAINT AQUA (-3350 3875);
FORCEPROP 1 LASTPIN (-3400 3875) $PN 1
J 0
(-3390 3855);
DISPLAY 0.787234 (-3390 3855);
PAINT ORANGE (-3390 3855);
FORCEPROP 1 LAST VALUE 47UF
J 0
(-3350 3825);
DISPLAY 0.617021 (-3350 3825);
PAINT SKYBLUE (-3350 3825);
FORCEPROP 1 LAST VOLTAGE 4V
J 0
(-3350 3775);
DISPLAY 0.638298 (-3350 3775);
PAINT SKYBLUE (-3350 3775);
FORCEPROP 1 LAST PART_NUMBER C95333-006
J 0
(-3350 3575);
DISPLAY 0.617021 (-3350 3575);
PAINT BLUE (-3350 3575);
FORCEPROP 0 LAST GROUP PWR_MLCC_CAP
J 0
(-3344 3437);
DISPLAY 0.638298 (-3344 3437);
PAINT BROWN (-3344 3437);
DISPLAY BOTH (-3344 3437);
FORCEPROP 0 LAST POP NOPOP
J 0
(-3350 3525);
DISPLAY 0.638298 (-3350 3525);
PAINT RED (-3350 3525);
FORCEPROP 1 LAST PACK_TYPE 0805
J 0
(-3350 3625);
DISPLAY 0.617021 (-3350 3625);
PAINT SKYBLUE (-3350 3625);
FORCEPROP 1 LAST MATERIAL X6S
J 0
(-3350 3675);
DISPLAY 0.617021 (-3350 3675);
PAINT SKYBLUE (-3350 3675);
FORCEPROP 1 LASTPIN (-3400 3675) $PN 2
J 0
(-3390 3655);
DISPLAY 0.787234 (-3390 3655);
PAINT ORANGE (-3390 3655);
FORCEPROP 1 LAST TOLERANCE 20%
J 0
(-3350 3725);
DISPLAY 0.617021 (-3350 3725);
PAINT SKYBLUE (-3350 3725);
FORCEPROP 2 LAST ROOM PVCCIN_CPU0_DECAP_VR
J 0
(-3350 3925);
DISPLAY 1.021277 (-3350 3925);
PAINT ORANGE (-3350 3925);
DISPLAY INVISIBLE (-3350 3925);
FORCEPROP 2 LAST BOM_COST PROC_SOCKET
J 0
(-3350 3975);
DISPLAY 1.021277 (-3350 3975);
PAINT ORANGE (-3350 3975);
DISPLAY INVISIBLE (-3350 3975);
FORCEPROP 1 LAST PATH I90
J 0
(-3350 3925);
DISPLAY 0.978723 (-3350 3925);
PAINT WHITE (-3350 3925);
DISPLAY INVISIBLE (-3350 3925);
FORCEPROP 2 LAST CDS_LIB mstr_discrete
J 0
(-3400 3775);
PAINT MONO (-3400 3775);
DISPLAY INVISIBLE (-3400 3775);
FORCEPROP 0 LAST SEC 1
J 0
(-3350 3925);
DISPLAY 0.680851 (-3350 3925);
PAINT MONO (-3350 3925);
DISPLAY INVISIBLE (-3350 3925);
FORCEPROP 2 LAST SEC_TYPE 0805
J 0
(-3350 3975);
DISPLAY 1.021277 (-3350 3975);
PAINT ORANGE (-3350 3975);
DISPLAY INVISIBLE (-3350 3975);
FORCEADD CAP..1
(-7350 3750);
FORCEPROP 1 LAST VOLTAGE 4V
J 0
(-7300 3750);
DISPLAY 0.638298 (-7300 3750);
PAINT SKYBLUE (-7300 3750);
FORCEPROP 1 LAST VALUE 47UF
J 0
(-7300 3800);
DISPLAY 0.617021 (-7300 3800);
PAINT SKYBLUE (-7300 3800);
FORCEPROP 1 LASTPIN (-7350 3850) $PN 1
J 0
(-7340 3830);
DISPLAY 0.787234 (-7340 3830);
PAINT ORANGE (-7340 3830);
FORCEPROP 1 LAST LOCATION C5G118
J 0
(-7300 3850);
DISPLAY 0.617021 (-7300 3850);
PAINT AQUA (-7300 3850);
FORCEPROP 1 LAST MATERIAL X6S
J 0
(-7300 3650);
DISPLAY 0.617021 (-7300 3650);
PAINT SKYBLUE (-7300 3650);
FORCEPROP 1 LAST TOLERANCE 20%
J 0
(-7300 3700);
DISPLAY 0.617021 (-7300 3700);
PAINT SKYBLUE (-7300 3700);
FORCEPROP 0 LAST POP NOPOP
J 0
(-7300 3500);
DISPLAY 0.638298 (-7300 3500);
PAINT RED (-7300 3500);
FORCEPROP 1 LAST PART_NUMBER C95333-006
J 0
(-7300 3550);
DISPLAY 0.617021 (-7300 3550);
PAINT BLUE (-7300 3550);
FORCEPROP 1 LAST PACK_TYPE 0805
J 0
(-7300 3600);
DISPLAY 0.617021 (-7300 3600);
PAINT SKYBLUE (-7300 3600);
FORCEPROP 1 LASTPIN (-7350 3650) $PN 2
J 0
(-7340 3630);
DISPLAY 0.787234 (-7340 3630);
PAINT ORANGE (-7340 3630);
FORCEPROP 0 LAST GROUP PWR_MLCC_CAP
J 0
(-7294 3412);
DISPLAY 0.638298 (-7294 3412);
PAINT BROWN (-7294 3412);
DISPLAY BOTH (-7294 3412);
FORCEPROP 2 LAST CDS_LIB mstr_discrete
J 0
(-7350 3750);
PAINT MONO (-7350 3750);
DISPLAY INVISIBLE (-7350 3750);
FORCEPROP 1 LAST PATH I91
J 0
(-7300 3900);
DISPLAY 0.978723 (-7300 3900);
PAINT WHITE (-7300 3900);
DISPLAY INVISIBLE (-7300 3900);
FORCEPROP 2 LAST ROOM PVCCIN_CPU0_DECAP_VR
J 0
(-7300 3900);
DISPLAY 1.021277 (-7300 3900);
PAINT ORANGE (-7300 3900);
DISPLAY INVISIBLE (-7300 3900);
FORCEPROP 2 LAST BOM_COST PROC_SOCKET
J 0
(-7300 3950);
DISPLAY 1.021277 (-7300 3950);
PAINT ORANGE (-7300 3950);
DISPLAY INVISIBLE (-7300 3950);
FORCEPROP 0 LAST SEC 1
J 0
(-7300 3900);
DISPLAY 0.680851 (-7300 3900);
PAINT MONO (-7300 3900);
DISPLAY INVISIBLE (-7300 3900);
FORCEPROP 2 LAST SEC_TYPE 0805
J 0
(-7300 3950);
DISPLAY 1.021277 (-7300 3950);
PAINT ORANGE (-7300 3950);
DISPLAY INVISIBLE (-7300 3950);
FORCEADD CAP..1
(-7750 3750);
FORCEPROP 0 LAST POP NOPOP
J 0
(-7700 3500);
DISPLAY 0.638298 (-7700 3500);
PAINT RED (-7700 3500);
FORCEPROP 1 LASTPIN (-7750 3650) $PN 2
J 0
(-7740 3630);
DISPLAY 0.787234 (-7740 3630);
PAINT ORANGE (-7740 3630);
FORCEPROP 1 LAST VOLTAGE 4V
J 0
(-7700 3750);
DISPLAY 0.638298 (-7700 3750);
PAINT SKYBLUE (-7700 3750);
FORCEPROP 1 LAST VALUE 47UF
J 0
(-7700 3800);
DISPLAY 0.617021 (-7700 3800);
PAINT SKYBLUE (-7700 3800);
FORCEPROP 1 LASTPIN (-7750 3850) $PN 1
J 0
(-7740 3830);
DISPLAY 0.787234 (-7740 3830);
PAINT ORANGE (-7740 3830);
FORCEPROP 1 LAST TOLERANCE 20%
J 0
(-7700 3700);
DISPLAY 0.617021 (-7700 3700);
PAINT SKYBLUE (-7700 3700);
FORCEPROP 1 LAST MATERIAL X6S
J 0
(-7700 3650);
DISPLAY 0.617021 (-7700 3650);
PAINT SKYBLUE (-7700 3650);
FORCEPROP 1 LAST PACK_TYPE 0805
J 0
(-7700 3600);
DISPLAY 0.617021 (-7700 3600);
PAINT SKYBLUE (-7700 3600);
FORCEPROP 1 LAST PART_NUMBER C95333-006
J 0
(-7700 3550);
DISPLAY 0.617021 (-7700 3550);
PAINT BLUE (-7700 3550);
FORCEPROP 0 LAST GROUP PWR_MLCC_CAP
J 0
(-7694 3462);
DISPLAY 0.638298 (-7694 3462);
PAINT BROWN (-7694 3462);
DISPLAY BOTH (-7694 3462);
FORCEPROP 1 LAST LOCATION C5G117
J 0
(-7700 3850);
DISPLAY 0.617021 (-7700 3850);
PAINT AQUA (-7700 3850);
FORCEPROP 2 LAST ROOM PVCCIN_CPU0_DECAP_VR
J 0
(-7700 3900);
DISPLAY 1.021277 (-7700 3900);
PAINT ORANGE (-7700 3900);
DISPLAY INVISIBLE (-7700 3900);
FORCEPROP 2 LAST BOM_COST PROC_SOCKET
J 0
(-7700 3950);
DISPLAY 1.021277 (-7700 3950);
PAINT ORANGE (-7700 3950);
DISPLAY INVISIBLE (-7700 3950);
FORCEPROP 1 LAST PATH I92
J 0
(-7700 3900);
DISPLAY 0.978723 (-7700 3900);
PAINT WHITE (-7700 3900);
DISPLAY INVISIBLE (-7700 3900);
FORCEPROP 2 LAST CDS_LIB mstr_discrete
J 0
(-7750 3750);
PAINT MONO (-7750 3750);
DISPLAY INVISIBLE (-7750 3750);
FORCEPROP 0 LAST SEC 1
J 0
(-7700 3900);
DISPLAY 0.680851 (-7700 3900);
PAINT MONO (-7700 3900);
DISPLAY INVISIBLE (-7700 3900);
FORCEPROP 2 LAST SEC_TYPE 0805
J 0
(-7700 3950);
DISPLAY 1.021277 (-7700 3950);
PAINT ORANGE (-7700 3950);
DISPLAY INVISIBLE (-7700 3950);
FORCEADD INTEL_CORP_BPAGE..1
(0 0);
FORCEPROP 1 LAST CDS_CON_LAST_MODIFIED Fri Jun 16 17:49:28 2017
J 0
(-1425 325);
PAINT ORANGE (-1425 325);
DISPLAY INVISIBLE (-1425 325);
FORCEPROP 1 LAST CUSTOM_TXT_CDS <CURRENT_DESIGN_SHEET> OF <TOTAL_DESIGN_SHEETS>
J 0
(-500 25);
PAINT ORANGE (-500 25);
FORCEPROP 1 LAST CUSTOM_TXT_CDS <CON_LAST_MODIFIED>
J 0
(-4000 100);
PAINT ORANGE (-4000 100);
FORCEPROP 2 LAST CUSTOM_TXT_CDS <XR_PAGE_TITLE>
J 0
(-7890 5250);
DISPLAY 0.638298 (-7890 5250);
PAINT PINK (-7890 5250);
DISPLAY INVISIBLE (-7890 5250);
FORCEPROP 1 LAST SCH_TITLE ADD DIMM CAP FOR SINGLE SIDE MB (2/2)
J 0
(-7950 50);
DISPLAY 2.468085 (-7950 50);
PAINT ORANGE (-7950 50);
FORCEPROP 2 LAST PAGE_BORDER TRUE
J 0
(-7890 5250);
DISPLAY 0.638298 (-7890 5250);
PAINT PINK (-7890 5250);
DISPLAY INVISIBLE (-7890 5250);
FORCEPROP 2 LAST CDS_LIB mstr_symbols
J 0
(0 0);
PAINT MONO (0 0);
DISPLAY INVISIBLE (0 0);
FORCEPROP 1 LAST COMMENT_BODY TRUE
J 0
(12 12);
DISPLAY 0.468085 (12 12);
PAINT GREEN (12 12);
DISPLAY INVISIBLE (12 12);
FORCEPROP 2 LAST CDS_XR_PAGE_TITLE CR-243 : @BASEBOARD_FAB2_LIB.BASEBOARD_FAB2(SCH_1):PAGE243
J 0
(-7890 5250);
DISPLAY 0.638298 (-7890 5250);
PAINT PINK (-7890 5250);
DISPLAY INVISIBLE (-7890 5250);
WIRE 16 -1 (-7750 1550)(-7750 1500);
WIRE 16 -1 (-7750 1550)(-7350 1550);
WIRE 16 -1 (-7750 1750)(-7750 1550);
WIRE 16 -1 (-6950 1550)(-7350 1550);
WIRE 16 -1 (-7350 1750)(-7350 1550);
WIRE 16 -1 (-6550 1550)(-6950 1550);
WIRE 16 -1 (-6950 1750)(-6950 1550);
WIRE 16 -1 (-6550 1550)(-6150 1550);
WIRE 16 -1 (-6550 1750)(-6550 1550);
WIRE 16 -1 (-5750 1550)(-6150 1550);
WIRE 16 -1 (-6150 1750)(-6150 1550);
WIRE 16 -1 (-5350 1550)(-5750 1550);
WIRE 16 -1 (-5750 1750)(-5750 1550);
WIRE 16 -1 (-4950 1550)(-5350 1550);
WIRE 16 -1 (-5350 1750)(-5350 1550);
WIRE 16 -1 (-4950 1550)(-4550 1550);
WIRE 16 -1 (-4950 1750)(-4950 1550);
WIRE 16 -1 (-4550 1750)(-4550 1550);
WIRE 16 -1 (-7750 3400)(-7750 3450);
WIRE 16 -1 (-7350 3450)(-7750 3450);
WIRE 16 -1 (-7750 3650)(-7750 3450);
WIRE 16 -1 (-7350 3450)(-7350 3650);
WIRE 16 -1 (-7750 3950)(-7750 4000);
WIRE 16 -1 (-7350 3950)(-7750 3950);
WIRE 16 -1 (-7750 3950)(-7750 3850);
WIRE 16 -1 (-7350 3850)(-7350 3950);
WIRE 16 -1 (-3800 1550)(-3800 1500);
WIRE 16 -1 (-3800 1550)(-3400 1550);
WIRE 16 -1 (-3800 1750)(-3800 1550);
WIRE 16 -1 (-3400 1550)(-3000 1550);
WIRE 16 -1 (-3400 1750)(-3400 1550);
WIRE 16 -1 (-3000 1550)(-2600 1550);
WIRE 16 -1 (-3000 1750)(-3000 1550);
WIRE 16 -1 (-2600 1550)(-2200 1550);
WIRE 16 -1 (-2600 1750)(-2600 1550);
WIRE 16 -1 (-2200 1550)(-1800 1550);
WIRE 16 -1 (-2200 1750)(-2200 1550);
WIRE 16 -1 (-1800 1550)(-1400 1550);
WIRE 16 -1 (-1800 1750)(-1800 1550);
WIRE 16 -1 (-1400 1550)(-1000 1550);
WIRE 16 -1 (-1400 1750)(-1400 1550);
WIRE 16 -1 (-600 1550)(-1000 1550);
WIRE 16 -1 (-1000 1750)(-1000 1550);
WIRE 16 -1 (-600 1750)(-600 1550);
WIRE 16 -1 (-3800 2050)(-3800 2100);
WIRE 16 -1 (-3800 2050)(-3400 2050);
WIRE 16 -1 (-3800 1950)(-3800 2050);
WIRE 16 -1 (-3400 2050)(-3000 2050);
WIRE 16 -1 (-3400 1950)(-3400 2050);
WIRE 16 -1 (-3000 2050)(-2600 2050);
WIRE 16 -1 (-3000 1950)(-3000 2050);
WIRE 16 -1 (-2600 2050)(-2200 2050);
WIRE 16 -1 (-2600 1950)(-2600 2050);
WIRE 16 -1 (-2200 2050)(-1800 2050);
WIRE 16 -1 (-2200 1950)(-2200 2050);
WIRE 16 -1 (-1800 2050)(-1400 2050);
WIRE 16 -1 (-1800 1950)(-1800 2050);
WIRE 16 -1 (-1400 2050)(-1000 2050);
WIRE 16 -1 (-1400 1950)(-1400 2050);
WIRE 16 -1 (-1000 2050)(-600 2050);
WIRE 16 -1 (-1000 1950)(-1000 2050);
WIRE 16 -1 (-600 1950)(-600 2050);
WIRE 16 -1 (-7750 2050)(-7750 2100);
WIRE 16 -1 (-7750 2050)(-7350 2050);
WIRE 16 -1 (-7750 1950)(-7750 2050);
WIRE 16 -1 (-6950 2050)(-7350 2050);
WIRE 16 -1 (-7350 1950)(-7350 2050);
WIRE 16 -1 (-6550 2050)(-6950 2050);
WIRE 16 -1 (-6950 1950)(-6950 2050);
WIRE 16 -1 (-6550 2050)(-6150 2050);
WIRE 16 -1 (-6550 1950)(-6550 2050);
WIRE 16 -1 (-5750 2050)(-6150 2050);
WIRE 16 -1 (-6150 1950)(-6150 2050);
WIRE 16 -1 (-5350 2050)(-5750 2050);
WIRE 16 -1 (-5750 1950)(-5750 2050);
WIRE 16 -1 (-4950 2050)(-5350 2050);
WIRE 16 -1 (-5350 1950)(-5350 2050);
WIRE 16 -1 (-4550 2050)(-4950 2050);
WIRE 16 -1 (-4950 1950)(-4950 2050);
WIRE 16 -1 (-4550 1950)(-4550 2050);
WIRE 16 -1 (-3800 2500)(-3800 2450);
WIRE 16 -1 (-3400 2500)(-3800 2500);
WIRE 16 -1 (-3800 2700)(-3800 2500);
WIRE 16 -1 (-3400 2500)(-3000 2500);
WIRE 16 -1 (-3400 2700)(-3400 2500);
WIRE 16 -1 (-3000 2500)(-2600 2500);
WIRE 16 -1 (-3000 2700)(-3000 2500);
WIRE 16 -1 (-2600 2500)(-2200 2500);
WIRE 16 -1 (-2600 2700)(-2600 2500);
WIRE 16 -1 (-2200 2500)(-1800 2500);
WIRE 16 -1 (-2200 2700)(-2200 2500);
WIRE 16 -1 (-1800 2500)(-1400 2500);
WIRE 16 -1 (-1800 2700)(-1800 2500);
WIRE 16 -1 (-1400 2500)(-1000 2500);
WIRE 16 -1 (-1400 2700)(-1400 2500);
WIRE 16 -1 (-600 2500)(-1000 2500);
WIRE 16 -1 (-1000 2700)(-1000 2500);
WIRE 16 -1 (-600 2700)(-600 2500);
WIRE 16 -1 (-3800 3000)(-3800 3050);
WIRE 16 -1 (-3800 3000)(-3400 3000);
WIRE 16 -1 (-3800 2900)(-3800 3000);
WIRE 16 -1 (-3400 3000)(-3000 3000);
WIRE 16 -1 (-3400 2900)(-3400 3000);
WIRE 16 -1 (-3000 3000)(-2600 3000);
WIRE 16 -1 (-3000 2900)(-3000 3000);
WIRE 16 -1 (-2600 3000)(-2200 3000);
WIRE 16 -1 (-2600 2900)(-2600 3000);
WIRE 16 -1 (-2200 3000)(-1800 3000);
WIRE 16 -1 (-2200 2900)(-2200 3000);
WIRE 16 -1 (-1800 3000)(-1400 3000);
WIRE 16 -1 (-1800 2900)(-1800 3000);
WIRE 16 -1 (-1400 3000)(-1000 3000);
WIRE 16 -1 (-1400 2900)(-1400 3000);
WIRE 16 -1 (-1000 3000)(-600 3000);
WIRE 16 -1 (-1000 2900)(-1000 3000);
WIRE 16 -1 (-600 2900)(-600 3000);
WIRE 16 -1 (-3800 3400)(-3800 3450);
WIRE 16 -1 (-3800 3450)(-3400 3450);
WIRE 16 -1 (-3800 3675)(-3800 3450);
WIRE 16 -1 (-3400 3450)(-3400 3675);
WIRE 16 -1 (-3800 4000)(-3800 3950);
WIRE 16 -1 (-3400 3950)(-3800 3950);
WIRE 16 -1 (-3800 3950)(-3800 3875);
WIRE 16 -1 (-3400 3875)(-3400 3950);
WIRE 16 -1 (-7750 2500)(-7750 2450);
WIRE 16 -1 (-7750 2500)(-7350 2500);
WIRE 16 -1 (-7750 2700)(-7750 2500);
WIRE 16 -1 (-6950 2500)(-7350 2500);
WIRE 16 -1 (-7350 2700)(-7350 2500);
WIRE 16 -1 (-6550 2500)(-6950 2500);
WIRE 16 -1 (-6950 2700)(-6950 2500);
WIRE 16 -1 (-6150 2500)(-6550 2500);
WIRE 16 -1 (-6550 2700)(-6550 2500);
WIRE 16 -1 (-5750 2500)(-6150 2500);
WIRE 16 -1 (-6150 2700)(-6150 2500);
WIRE 16 -1 (-5350 2500)(-5750 2500);
WIRE 16 -1 (-5750 2700)(-5750 2500);
WIRE 16 -1 (-4950 2500)(-5350 2500);
WIRE 16 -1 (-5350 2700)(-5350 2500);
WIRE 16 -1 (-4950 2500)(-4550 2500);
WIRE 16 -1 (-4950 2700)(-4950 2500);
WIRE 16 -1 (-4550 2675)(-4550 2500);
WIRE 16 -1 (-7750 3000)(-7750 3050);
WIRE 16 -1 (-7750 3000)(-7350 3000);
WIRE 16 -1 (-7750 2900)(-7750 3000);
WIRE 16 -1 (-6950 3000)(-7350 3000);
WIRE 16 -1 (-7350 2900)(-7350 3000);
WIRE 16 -1 (-6550 3000)(-6950 3000);
WIRE 16 -1 (-6950 2900)(-6950 3000);
WIRE 16 -1 (-6150 3000)(-6550 3000);
WIRE 16 -1 (-6550 3000)(-6550 2900);
WIRE 16 -1 (-5750 3000)(-6150 3000);
WIRE 16 -1 (-6150 2900)(-6150 3000);
WIRE 16 -1 (-5350 3000)(-5750 3000);
WIRE 16 -1 (-5750 2900)(-5750 3000);
WIRE 16 -1 (-4950 3000)(-5350 3000);
WIRE 16 -1 (-5350 2900)(-5350 3000);
WIRE 16 -1 (-4550 3000)(-4950 3000);
WIRE 16 -1 (-4950 2900)(-4950 3000);
WIRE 16 -1 (-4550 2875)(-4550 3000);
WIRE 3 682 (-7900 3300)(-6850 3300);
WIRE 3 682 (-7900 4150)(-7900 3300);
WIRE 3 682 (-6850 3300)(-6850 4150);
WIRE 3 682 (-6850 4150)(-7900 4150);
WIRE 3 682 (-4000 3300)(-2850 3300);
WIRE 3 682 (-4000 4150)(-4000 3300);
WIRE 3 682 (-2850 3300)(-2850 4150);
WIRE 3 682 (-2850 4150)(-4000 4150);
DOT 1 (-3800 2500);
DOT 1 (-3800 3000);
DOT 1 (-3800 3950);
DOT 1 (-3400 2500);
DOT 1 (-3000 2500);
DOT 1 (-3400 3000);
DOT 1 (-3000 3000);
DOT 1 (-2600 2500);
DOT 1 (-2600 3000);
DOT 1 (-4950 2500);
DOT 1 (-4950 3000);
DOT 1 (-5350 2500);
DOT 1 (-5350 3000);
DOT 1 (-5750 2500);
DOT 1 (-5750 3000);
DOT 1 (-6150 2500);
DOT 1 (-6150 3000);
DOT 1 (-6550 2500);
DOT 1 (-6550 3000);
DOT 1 (-6950 2500);
DOT 1 (-6950 3000);
DOT 1 (-7350 3000);
DOT 1 (-7750 1550);
DOT 1 (-7750 2050);
DOT 1 (-7750 3000);
DOT 1 (-7750 3450);
DOT 1 (-7750 3950);
DOT 1 (-7750 2500);
DOT 1 (-2200 3000);
DOT 1 (-1800 3000);
DOT 1 (-1800 2500);
DOT 1 (-1400 3000);
DOT 1 (-1400 2500);
DOT 1 (-1000 3000);
DOT 1 (-1000 2500);
DOT 1 (-7350 2050);
DOT 1 (-7350 1550);
DOT 1 (-6950 2050);
DOT 1 (-6550 2050);
DOT 1 (-6550 1550);
DOT 1 (-6150 2050);
DOT 1 (-6150 1550);
DOT 1 (-5750 2050);
DOT 1 (-5750 1550);
DOT 1 (-5350 2050);
DOT 1 (-5350 1550);
DOT 1 (-4950 2050);
DOT 1 (-4950 1550);
DOT 1 (-6950 1550);
DOT 1 (-3800 1550);
DOT 1 (-3400 2050);
DOT 1 (-3400 1550);
DOT 1 (-3000 2050);
DOT 1 (-3000 1550);
DOT 1 (-2600 2050);
DOT 1 (-2600 1550);
DOT 1 (-2200 1550);
DOT 1 (-1800 2050);
DOT 1 (-1800 1550);
DOT 1 (-1400 1550);
DOT 1 (-1000 2050);
DOT 1 (-1000 1550);
DOT 1 (-2200 2050);
DOT 1 (-2200 2500);
DOT 1 (-3800 3450);
DOT 1 (-7350 2500);
DOT 1 (-3800 2050);
DOT 1 (-1400 2050);
FORCENOTE
TP FAB1 ADD CAP ON DIMM BOTTOM SIDE 1116
(-4834 692) 0;
DISPLAY LEFT (-4834 692);
DISPLAY 1.021277 (-4834 692);
PAINT RED (-4834 692);
FORCENOTE
TP FAB3-DVT NOPOP 20161220
(-4000 3250) 0;
DISPLAY LEFT (-4000 3250);
DISPLAY 0.638298 (-4000 3250);
PAINT RED (-4000 3250);
FORCENOTE
TP FAB3-DVT NOPOP 20161220
(-7900 3250) 0;
DISPLAY LEFT (-7900 3250);
DISPLAY 0.638298 (-7900 3250);
PAINT RED (-7900 3250);
QUIT
